FILE_TYPE = MACRO_DRAWING;
SET COLOR_WIRE YELLOW;
SET COLOR_PROP ORANGE;
SET COLOR_DOT WHITE;
SET COLOR_ARC YELLOW;
SET COLOR_BODY GREEN;
SET COLOR_NOTE PURPLE;
SET PROP_DISPLAY VALUE;
SET PAGE_NUMBER P38;
FORCEADD GENOA_SP5..2
(-4725 3625);
FORCEPROP 1 LAST LOCATION U26
J 0
(-5370 6481);
DISPLAY 0.489362 (-5370 6481);
PAINT SKYBLUE (-5370 6481);
FORCEPROP 0 LAST $SEC 2
J 0
(-5350 6525);
DISPLAY 0.680851 (-5350 6525);
PAINT MONO (-5350 6525);
DISPLAY INVISIBLE (-5350 6525);
FORCEPROP 0 LAST CDS_SEC 2
J 0
(-5375 6425);
DISPLAY 1.021277 (-5375 6425);
DISPLAY INVISIBLE (-5375 6425);
FORCEPROP 0 LASTPIN (-5525 3025) $PN BC64
J 2
(-5535 3035);
DISPLAY 0.489362 (-5535 3035);
PAINT MONO (-5535 3035);
FORCEPROP 0 LASTPIN (-5525 2975) $PN BD63
J 2
(-5535 2985);
DISPLAY 0.489362 (-5535 2985);
PAINT MONO (-5535 2985);
FORCEPROP 0 LASTPIN (-5525 1875) $PN BF63
J 2
(-5535 1885);
DISPLAY 0.489362 (-5535 1885);
PAINT MONO (-5535 1885);
FORCEPROP 0 LASTPIN (-5525 1825) $PN BG64
J 2
(-5535 1835);
DISPLAY 0.489362 (-5535 1835);
PAINT MONO (-5535 1835);
FORCEPROP 0 LASTPIN (-5525 2175) $PN AT62
J 2
(-5535 2185);
DISPLAY 0.489362 (-5535 2185);
PAINT MONO (-5535 2185);
FORCEPROP 0 LASTPIN (-5525 2075) $PN AU62
J 2
(-5535 2085);
DISPLAY 0.489362 (-5535 2085);
PAINT MONO (-5535 2085);
FORCEPROP 0 LASTPIN (-5525 2875) $PN AV63
J 2
(-5535 2885);
DISPLAY 0.489362 (-5535 2885);
PAINT MONO (-5535 2885);
FORCEPROP 0 LASTPIN (-5525 2825) $PN AW62
J 2
(-5535 2835);
DISPLAY 0.489362 (-5535 2835);
PAINT MONO (-5535 2835);
FORCEPROP 0 LASTPIN (-5525 2725) $PN BN62
J 2
(-5535 2735);
DISPLAY 0.489362 (-5535 2735);
PAINT MONO (-5535 2735);
FORCEPROP 0 LASTPIN (-5525 1725) $PN AU64
J 2
(-5535 1735);
DISPLAY 0.489362 (-5535 1735);
PAINT MONO (-5535 1735);
FORCEPROP 0 LASTPIN (-5525 1675) $PN AV62
J 2
(-5535 1685);
DISPLAY 0.489362 (-5535 1685);
PAINT MONO (-5535 1685);
FORCEPROP 0 LASTPIN (-5525 1575) $PN BP62
J 2
(-5535 1585);
DISPLAY 0.489362 (-5535 1585);
PAINT MONO (-5535 1585);
FORCEPROP 0 LASTPIN (-5525 3875) $PN AW64
J 2
(-5535 3885);
DISPLAY 0.489362 (-5535 3885);
PAINT MONO (-5535 3885);
FORCEPROP 0 LASTPIN (-5525 3825) $PN AY63
J 2
(-5535 3835);
DISPLAY 0.489362 (-5535 3835);
PAINT MONO (-5535 3835);
FORCEPROP 0 LASTPIN (-5525 3775) $PN AY62
J 2
(-5535 3785);
DISPLAY 0.489362 (-5535 3785);
PAINT MONO (-5535 3785);
FORCEPROP 0 LASTPIN (-5525 3725) $PN BA62
J 2
(-5535 3735);
DISPLAY 0.489362 (-5535 3735);
PAINT MONO (-5535 3735);
FORCEPROP 0 LASTPIN (-5525 3675) $PN BA64
J 2
(-5535 3685);
DISPLAY 0.489362 (-5535 3685);
PAINT MONO (-5535 3685);
FORCEPROP 0 LASTPIN (-5525 3625) $PN BB63
J 2
(-5535 3635);
DISPLAY 0.489362 (-5535 3635);
PAINT MONO (-5535 3635);
FORCEPROP 0 LASTPIN (-5525 3575) $PN BB62
J 2
(-5535 3585);
DISPLAY 0.489362 (-5535 3585);
PAINT MONO (-5535 3585);
FORCEPROP 0 LASTPIN (-3925 2425) $PN AJ64
J 0
(-3915 2435);
DISPLAY 0.489362 (-3915 2435);
PAINT MONO (-3915 2435);
FORCEPROP 0 LASTPIN (-3925 2375) $PN AK62
J 0
(-3915 2385);
DISPLAY 0.489362 (-3915 2385);
PAINT MONO (-3915 2385);
FORCEPROP 0 LASTPIN (-3925 2325) $PN AK63
J 0
(-3915 2335);
DISPLAY 0.489362 (-3915 2335);
PAINT MONO (-3915 2335);
FORCEPROP 0 LASTPIN (-3925 2275) $PN AL62
J 0
(-3915 2285);
DISPLAY 0.489362 (-3915 2285);
PAINT MONO (-3915 2285);
FORCEPROP 0 LASTPIN (-3925 2225) $PN AN64
J 0
(-3915 2235);
DISPLAY 0.489362 (-3915 2235);
PAINT MONO (-3915 2235);
FORCEPROP 0 LASTPIN (-3925 2175) $PN AP62
J 0
(-3915 2185);
DISPLAY 0.489362 (-3915 2185);
PAINT MONO (-3915 2185);
FORCEPROP 0 LASTPIN (-3925 2125) $PN AP63
J 0
(-3915 2135);
DISPLAY 0.489362 (-3915 2135);
PAINT MONO (-3915 2135);
FORCEPROP 0 LASTPIN (-3925 2075) $PN AR62
J 0
(-3915 2085);
DISPLAY 0.489362 (-3915 2085);
PAINT MONO (-3915 2085);
FORCEPROP 0 LASTPIN (-3925 6025) $PN E64
J 0
(-3915 6035);
DISPLAY 0.489362 (-3915 6035);
PAINT MONO (-3915 6035);
FORCEPROP 0 LASTPIN (-3925 5975) $PN F62
J 0
(-3915 5985);
DISPLAY 0.489362 (-3915 5985);
PAINT MONO (-3915 5985);
FORCEPROP 0 LASTPIN (-3925 5925) $PN F63
J 0
(-3915 5935);
DISPLAY 0.489362 (-3915 5935);
PAINT MONO (-3915 5935);
FORCEPROP 0 LASTPIN (-3925 5875) $PN G62
J 0
(-3915 5885);
DISPLAY 0.489362 (-3915 5885);
PAINT MONO (-3915 5885);
FORCEPROP 0 LASTPIN (-3925 5825) $PN J64
J 0
(-3915 5835);
DISPLAY 0.489362 (-3915 5835);
PAINT MONO (-3915 5835);
FORCEPROP 0 LASTPIN (-3925 5775) $PN K62
J 0
(-3915 5785);
DISPLAY 0.489362 (-3915 5785);
PAINT MONO (-3915 5785);
FORCEPROP 0 LASTPIN (-3925 5725) $PN K63
J 0
(-3915 5735);
DISPLAY 0.489362 (-3915 5735);
PAINT MONO (-3915 5735);
FORCEPROP 0 LASTPIN (-3925 5675) $PN L62
J 0
(-3915 5685);
DISPLAY 0.489362 (-3915 5685);
PAINT MONO (-3915 5685);
FORCEPROP 0 LASTPIN (-3925 5575) $PN L64
J 0
(-3915 5585);
DISPLAY 0.489362 (-3915 5585);
PAINT MONO (-3915 5585);
FORCEPROP 0 LASTPIN (-3925 5525) $PN M62
J 0
(-3915 5535);
DISPLAY 0.489362 (-3915 5535);
PAINT MONO (-3915 5535);
FORCEPROP 0 LASTPIN (-3925 5475) $PN M63
J 0
(-3915 5485);
DISPLAY 0.489362 (-3915 5485);
PAINT MONO (-3915 5485);
FORCEPROP 0 LASTPIN (-3925 5425) $PN N62
J 0
(-3915 5435);
DISPLAY 0.489362 (-3915 5435);
PAINT MONO (-3915 5435);
FORCEPROP 0 LASTPIN (-3925 5375) $PN R64
J 0
(-3915 5385);
DISPLAY 0.489362 (-3915 5385);
PAINT MONO (-3915 5385);
FORCEPROP 0 LASTPIN (-3925 5325) $PN T62
J 0
(-3915 5335);
DISPLAY 0.489362 (-3915 5335);
PAINT MONO (-3915 5335);
FORCEPROP 0 LASTPIN (-3925 5275) $PN T63
J 0
(-3915 5285);
DISPLAY 0.489362 (-3915 5285);
PAINT MONO (-3915 5285);
FORCEPROP 0 LASTPIN (-3925 5225) $PN U62
J 0
(-3915 5235);
DISPLAY 0.489362 (-3915 5235);
PAINT MONO (-3915 5235);
FORCEPROP 0 LASTPIN (-3925 5125) $PN U64
J 0
(-3915 5135);
DISPLAY 0.489362 (-3915 5135);
PAINT MONO (-3915 5135);
FORCEPROP 0 LASTPIN (-3925 5075) $PN V62
J 0
(-3915 5085);
DISPLAY 0.489362 (-3915 5085);
PAINT MONO (-3915 5085);
FORCEPROP 0 LASTPIN (-3925 5025) $PN V63
J 0
(-3915 5035);
DISPLAY 0.489362 (-3915 5035);
PAINT MONO (-3915 5035);
FORCEPROP 0 LASTPIN (-3925 4975) $PN W62
J 0
(-3915 4985);
DISPLAY 0.489362 (-3915 4985);
PAINT MONO (-3915 4985);
FORCEPROP 0 LASTPIN (-3925 4925) $PN AA64
J 0
(-3915 4935);
DISPLAY 0.489362 (-3915 4935);
PAINT MONO (-3915 4935);
FORCEPROP 0 LASTPIN (-3925 4875) $PN AB62
J 0
(-3915 4885);
DISPLAY 0.489362 (-3915 4885);
PAINT MONO (-3915 4885);
FORCEPROP 0 LASTPIN (-3925 4825) $PN AB63
J 0
(-3915 4835);
DISPLAY 0.489362 (-3915 4835);
PAINT MONO (-3915 4835);
FORCEPROP 0 LASTPIN (-3925 4775) $PN AC62
J 0
(-3915 4785);
DISPLAY 0.489362 (-3915 4785);
PAINT MONO (-3915 4785);
FORCEPROP 0 LASTPIN (-3925 4675) $PN AC64
J 0
(-3915 4685);
DISPLAY 0.489362 (-3915 4685);
PAINT MONO (-3915 4685);
FORCEPROP 0 LASTPIN (-3925 4625) $PN AD62
J 0
(-3915 4635);
DISPLAY 0.489362 (-3915 4635);
PAINT MONO (-3915 4635);
FORCEPROP 0 LASTPIN (-3925 4575) $PN AD63
J 0
(-3915 4585);
DISPLAY 0.489362 (-3915 4585);
PAINT MONO (-3915 4585);
FORCEPROP 0 LASTPIN (-3925 4525) $PN AE62
J 0
(-3915 4535);
DISPLAY 0.489362 (-3915 4535);
PAINT MONO (-3915 4535);
FORCEPROP 0 LASTPIN (-3925 4475) $PN AG64
J 0
(-3915 4485);
DISPLAY 0.489362 (-3915 4485);
PAINT MONO (-3915 4485);
FORCEPROP 0 LASTPIN (-3925 4425) $PN AH62
J 0
(-3915 4435);
DISPLAY 0.489362 (-3915 4435);
PAINT MONO (-3915 4435);
FORCEPROP 0 LASTPIN (-3925 4375) $PN AH63
J 0
(-3915 4385);
DISPLAY 0.489362 (-3915 4385);
PAINT MONO (-3915 4385);
FORCEPROP 0 LASTPIN (-3925 4325) $PN AJ62
J 0
(-3915 4335);
DISPLAY 0.489362 (-3915 4335);
PAINT MONO (-3915 4335);
FORCEPROP 0 LASTPIN (-5525 6025) $PN G64
J 2
(-5535 6035);
DISPLAY 0.489362 (-5535 6035);
PAINT MONO (-5535 6035);
FORCEPROP 0 LASTPIN (-5525 5925) $PN N64
J 2
(-5535 5935);
DISPLAY 0.489362 (-5535 5935);
PAINT MONO (-5535 5935);
FORCEPROP 0 LASTPIN (-5525 5825) $PN W64
J 2
(-5535 5835);
DISPLAY 0.489362 (-5535 5835);
PAINT MONO (-5535 5835);
FORCEPROP 0 LASTPIN (-5525 5725) $PN AE64
J 2
(-5535 5735);
DISPLAY 0.489362 (-5535 5735);
PAINT MONO (-5535 5735);
FORCEPROP 0 LASTPIN (-5525 5625) $PN AL64
J 2
(-5535 5635);
DISPLAY 0.489362 (-5535 5635);
PAINT MONO (-5535 5635);
FORCEPROP 0 LASTPIN (-5525 5525) $PN J62
J 2
(-5535 5535);
DISPLAY 0.489362 (-5535 5535);
PAINT MONO (-5535 5535);
FORCEPROP 0 LASTPIN (-5525 5425) $PN R62
J 2
(-5535 5435);
DISPLAY 0.489362 (-5535 5435);
PAINT MONO (-5535 5435);
FORCEPROP 0 LASTPIN (-5525 5325) $PN AA62
J 2
(-5535 5335);
DISPLAY 0.489362 (-5535 5335);
PAINT MONO (-5535 5335);
FORCEPROP 0 LASTPIN (-5525 5225) $PN AG62
J 2
(-5535 5235);
DISPLAY 0.489362 (-5535 5235);
PAINT MONO (-5535 5235);
FORCEPROP 0 LASTPIN (-5525 5125) $PN AN62
J 2
(-5535 5135);
DISPLAY 0.489362 (-5535 5135);
PAINT MONO (-5535 5135);
FORCEPROP 0 LASTPIN (-5525 5975) $PN H63
J 2
(-5535 5985);
DISPLAY 0.489362 (-5535 5985);
PAINT MONO (-5535 5985);
FORCEPROP 0 LASTPIN (-5525 5875) $PN P63
J 2
(-5535 5885);
DISPLAY 0.489362 (-5535 5885);
PAINT MONO (-5535 5885);
FORCEPROP 0 LASTPIN (-5525 5775) $PN Y63
J 2
(-5535 5785);
DISPLAY 0.489362 (-5535 5785);
PAINT MONO (-5535 5785);
FORCEPROP 0 LASTPIN (-5525 5675) $PN AF63
J 2
(-5535 5685);
DISPLAY 0.489362 (-5535 5685);
PAINT MONO (-5535 5685);
FORCEPROP 0 LASTPIN (-5525 5575) $PN AM63
J 2
(-5535 5585);
DISPLAY 0.489362 (-5535 5585);
PAINT MONO (-5535 5585);
FORCEPROP 0 LASTPIN (-5525 5475) $PN H62
J 2
(-5535 5485);
DISPLAY 0.489362 (-5535 5485);
PAINT MONO (-5535 5485);
FORCEPROP 0 LASTPIN (-5525 5375) $PN P62
J 2
(-5535 5385);
DISPLAY 0.489362 (-5535 5385);
PAINT MONO (-5535 5385);
FORCEPROP 0 LASTPIN (-5525 5275) $PN Y62
J 2
(-5535 5285);
DISPLAY 0.489362 (-5535 5285);
PAINT MONO (-5535 5285);
FORCEPROP 0 LASTPIN (-5525 5175) $PN AF62
J 2
(-5535 5185);
DISPLAY 0.489362 (-5535 5185);
PAINT MONO (-5535 5185);
FORCEPROP 0 LASTPIN (-5525 5075) $PN AM62
J 2
(-5535 5085);
DISPLAY 0.489362 (-5535 5085);
PAINT MONO (-5535 5085);
FORCEPROP 0 LASTPIN (-5525 2625) $PN BC62
J 2
(-5535 2635);
DISPLAY 0.489362 (-5535 2635);
PAINT MONO (-5535 2635);
FORCEPROP 0 LASTPIN (-5525 2525) $PN BM62
J 2
(-5535 2535);
DISPLAY 0.489362 (-5535 2535);
PAINT MONO (-5535 2535);
FORCEPROP 0 LASTPIN (-5525 2475) $PN BN64
J 2
(-5535 2485);
DISPLAY 0.489362 (-5535 2485);
PAINT MONO (-5535 2485);
FORCEPROP 0 LASTPIN (-5525 2375) $PN BP63
J 2
(-5535 2385);
DISPLAY 0.489362 (-5535 2385);
PAINT MONO (-5535 2385);
FORCEPROP 0 LASTPIN (-5525 1475) $PN BL62
J 2
(-5535 1485);
DISPLAY 0.489362 (-5535 1485);
PAINT MONO (-5535 1485);
FORCEPROP 0 LASTPIN (-5525 1425) $PN BM63
J 2
(-5535 1435);
DISPLAY 0.489362 (-5535 1435);
PAINT MONO (-5535 1435);
FORCEPROP 0 LASTPIN (-5525 1325) $PN BR64
J 2
(-5535 1335);
DISPLAY 0.489362 (-5535 1335);
PAINT MONO (-5535 1335);
FORCEPROP 0 LASTPIN (-5525 3475) $PN BG62
J 2
(-5535 3485);
DISPLAY 0.489362 (-5535 3485);
PAINT MONO (-5535 3485);
FORCEPROP 0 LASTPIN (-5525 3425) $PN BH62
J 2
(-5535 3435);
DISPLAY 0.489362 (-5535 3435);
PAINT MONO (-5535 3435);
FORCEPROP 0 LASTPIN (-5525 3375) $PN BH63
J 2
(-5535 3385);
DISPLAY 0.489362 (-5535 3385);
PAINT MONO (-5535 3385);
FORCEPROP 0 LASTPIN (-5525 3325) $PN BJ64
J 2
(-5535 3335);
DISPLAY 0.489362 (-5535 3335);
PAINT MONO (-5535 3335);
FORCEPROP 0 LASTPIN (-5525 3275) $PN BJ62
J 2
(-5535 3285);
DISPLAY 0.489362 (-5535 3285);
PAINT MONO (-5535 3285);
FORCEPROP 0 LASTPIN (-5525 3225) $PN BK62
J 2
(-5535 3235);
DISPLAY 0.489362 (-5535 3235);
PAINT MONO (-5535 3235);
FORCEPROP 0 LASTPIN (-5525 3175) $PN BK63
J 2
(-5535 3185);
DISPLAY 0.489362 (-5535 3185);
PAINT MONO (-5535 3185);
FORCEPROP 0 LASTPIN (-3925 1975) $PN BY63
J 0
(-3915 1985);
DISPLAY 0.489362 (-3915 1985);
PAINT MONO (-3915 1985);
FORCEPROP 0 LASTPIN (-3925 1925) $PN CA62
J 0
(-3915 1935);
DISPLAY 0.489362 (-3915 1935);
PAINT MONO (-3915 1935);
FORCEPROP 0 LASTPIN (-3925 1875) $PN CA64
J 0
(-3915 1885);
DISPLAY 0.489362 (-3915 1885);
PAINT MONO (-3915 1885);
FORCEPROP 0 LASTPIN (-3925 1825) $PN CB62
J 0
(-3915 1835);
DISPLAY 0.489362 (-3915 1835);
PAINT MONO (-3915 1835);
FORCEPROP 0 LASTPIN (-3925 1775) $PN BT63
J 0
(-3915 1785);
DISPLAY 0.489362 (-3915 1785);
PAINT MONO (-3915 1785);
FORCEPROP 0 LASTPIN (-3925 1725) $PN BU62
J 0
(-3915 1735);
DISPLAY 0.489362 (-3915 1735);
PAINT MONO (-3915 1735);
FORCEPROP 0 LASTPIN (-3925 1675) $PN BU64
J 0
(-3915 1685);
DISPLAY 0.489362 (-3915 1685);
PAINT MONO (-3915 1685);
FORCEPROP 0 LASTPIN (-3925 1625) $PN BV62
J 0
(-3915 1635);
DISPLAY 0.489362 (-3915 1635);
PAINT MONO (-3915 1635);
FORCEPROP 0 LASTPIN (-3925 4225) $PN CB63
J 0
(-3915 4235);
DISPLAY 0.489362 (-3915 4235);
PAINT MONO (-3915 4235);
FORCEPROP 0 LASTPIN (-3925 4175) $PN CC62
J 0
(-3915 4185);
DISPLAY 0.489362 (-3915 4185);
PAINT MONO (-3915 4185);
FORCEPROP 0 LASTPIN (-3925 4125) $PN CC64
J 0
(-3915 4135);
DISPLAY 0.489362 (-3915 4135);
PAINT MONO (-3915 4135);
FORCEPROP 0 LASTPIN (-3925 4075) $PN CD62
J 0
(-3915 4085);
DISPLAY 0.489362 (-3915 4085);
PAINT MONO (-3915 4085);
FORCEPROP 0 LASTPIN (-3925 4025) $PN CF63
J 0
(-3915 4035);
DISPLAY 0.489362 (-3915 4035);
PAINT MONO (-3915 4035);
FORCEPROP 0 LASTPIN (-3925 3975) $PN CG62
J 0
(-3915 3985);
DISPLAY 0.489362 (-3915 3985);
PAINT MONO (-3915 3985);
FORCEPROP 0 LASTPIN (-3925 3925) $PN CG64
J 0
(-3915 3935);
DISPLAY 0.489362 (-3915 3935);
PAINT MONO (-3915 3935);
FORCEPROP 0 LASTPIN (-3925 3875) $PN CH62
J 0
(-3915 3885);
DISPLAY 0.489362 (-3915 3885);
PAINT MONO (-3915 3885);
FORCEPROP 0 LASTPIN (-3925 3775) $PN CH63
J 0
(-3915 3785);
DISPLAY 0.489362 (-3915 3785);
PAINT MONO (-3915 3785);
FORCEPROP 0 LASTPIN (-3925 3725) $PN CJ62
J 0
(-3915 3735);
DISPLAY 0.489362 (-3915 3735);
PAINT MONO (-3915 3735);
FORCEPROP 0 LASTPIN (-3925 3675) $PN CJ64
J 0
(-3915 3685);
DISPLAY 0.489362 (-3915 3685);
PAINT MONO (-3915 3685);
FORCEPROP 0 LASTPIN (-3925 3625) $PN CK62
J 0
(-3915 3635);
DISPLAY 0.489362 (-3915 3635);
PAINT MONO (-3915 3635);
FORCEPROP 0 LASTPIN (-3925 3575) $PN CM63
J 0
(-3915 3585);
DISPLAY 0.489362 (-3915 3585);
PAINT MONO (-3915 3585);
FORCEPROP 0 LASTPIN (-3925 3525) $PN CN62
J 0
(-3915 3535);
DISPLAY 0.489362 (-3915 3535);
PAINT MONO (-3915 3535);
FORCEPROP 0 LASTPIN (-3925 3475) $PN CN64
J 0
(-3915 3485);
DISPLAY 0.489362 (-3915 3485);
PAINT MONO (-3915 3485);
FORCEPROP 0 LASTPIN (-3925 3425) $PN CP62
J 0
(-3915 3435);
DISPLAY 0.489362 (-3915 3435);
PAINT MONO (-3915 3435);
FORCEPROP 0 LASTPIN (-3925 3325) $PN CP63
J 0
(-3915 3335);
DISPLAY 0.489362 (-3915 3335);
PAINT MONO (-3915 3335);
FORCEPROP 0 LASTPIN (-3925 3275) $PN CR62
J 0
(-3915 3285);
DISPLAY 0.489362 (-3915 3285);
PAINT MONO (-3915 3285);
FORCEPROP 0 LASTPIN (-3925 3225) $PN CR64
J 0
(-3915 3235);
DISPLAY 0.489362 (-3915 3235);
PAINT MONO (-3915 3235);
FORCEPROP 0 LASTPIN (-3925 3175) $PN CT62
J 0
(-3915 3185);
DISPLAY 0.489362 (-3915 3185);
PAINT MONO (-3915 3185);
FORCEPROP 0 LASTPIN (-3925 3125) $PN CV63
J 0
(-3915 3135);
DISPLAY 0.489362 (-3915 3135);
PAINT MONO (-3915 3135);
FORCEPROP 0 LASTPIN (-3925 3075) $PN CW62
J 0
(-3915 3085);
DISPLAY 0.489362 (-3915 3085);
PAINT MONO (-3915 3085);
FORCEPROP 0 LASTPIN (-3925 3025) $PN CW64
J 0
(-3915 3035);
DISPLAY 0.489362 (-3915 3035);
PAINT MONO (-3915 3035);
FORCEPROP 0 LASTPIN (-3925 2975) $PN CY62
J 0
(-3915 2985);
DISPLAY 0.489362 (-3915 2985);
PAINT MONO (-3915 2985);
FORCEPROP 0 LASTPIN (-3925 2875) $PN CY63
J 0
(-3915 2885);
DISPLAY 0.489362 (-3915 2885);
PAINT MONO (-3915 2885);
FORCEPROP 0 LASTPIN (-3925 2825) $PN DA62
J 0
(-3915 2835);
DISPLAY 0.489362 (-3915 2835);
PAINT MONO (-3915 2835);
FORCEPROP 0 LASTPIN (-3925 2775) $PN DA64
J 0
(-3915 2785);
DISPLAY 0.489362 (-3915 2785);
PAINT MONO (-3915 2785);
FORCEPROP 0 LASTPIN (-3925 2725) $PN DB62
J 0
(-3915 2735);
DISPLAY 0.489362 (-3915 2735);
PAINT MONO (-3915 2735);
FORCEPROP 0 LASTPIN (-3925 2675) $PN DD63
J 0
(-3915 2685);
DISPLAY 0.489362 (-3915 2685);
PAINT MONO (-3915 2685);
FORCEPROP 0 LASTPIN (-3925 2625) $PN DE62
J 0
(-3915 2635);
DISPLAY 0.489362 (-3915 2635);
PAINT MONO (-3915 2635);
FORCEPROP 0 LASTPIN (-3925 2575) $PN DE64
J 0
(-3915 2585);
DISPLAY 0.489362 (-3915 2585);
PAINT MONO (-3915 2585);
FORCEPROP 0 LASTPIN (-3925 2525) $PN DF62
J 0
(-3915 2535);
DISPLAY 0.489362 (-3915 2535);
PAINT MONO (-3915 2535);
FORCEPROP 0 LASTPIN (-5525 4975) $PN CD63
J 2
(-5535 4985);
DISPLAY 0.489362 (-5535 4985);
PAINT MONO (-5535 4985);
FORCEPROP 0 LASTPIN (-5525 4875) $PN CK63
J 2
(-5535 4885);
DISPLAY 0.489362 (-5535 4885);
PAINT MONO (-5535 4885);
FORCEPROP 0 LASTPIN (-5525 4775) $PN CT63
J 2
(-5535 4785);
DISPLAY 0.489362 (-5535 4785);
PAINT MONO (-5535 4785);
FORCEPROP 0 LASTPIN (-5525 4675) $PN DB63
J 2
(-5535 4685);
DISPLAY 0.489362 (-5535 4685);
PAINT MONO (-5535 4685);
FORCEPROP 0 LASTPIN (-5525 4575) $PN BY62
J 2
(-5535 4585);
DISPLAY 0.489362 (-5535 4585);
PAINT MONO (-5535 4585);
FORCEPROP 0 LASTPIN (-5525 4475) $PN CF62
J 2
(-5535 4485);
DISPLAY 0.489362 (-5535 4485);
PAINT MONO (-5535 4485);
FORCEPROP 0 LASTPIN (-5525 4375) $PN CM62
J 2
(-5535 4385);
DISPLAY 0.489362 (-5535 4385);
PAINT MONO (-5535 4385);
FORCEPROP 0 LASTPIN (-5525 4275) $PN CV62
J 2
(-5535 4285);
DISPLAY 0.489362 (-5535 4285);
PAINT MONO (-5535 4285);
FORCEPROP 0 LASTPIN (-5525 4175) $PN DD62
J 2
(-5535 4185);
DISPLAY 0.489362 (-5535 4185);
PAINT MONO (-5535 4185);
FORCEPROP 0 LASTPIN (-5525 4075) $PN BV63
J 2
(-5535 4085);
DISPLAY 0.489362 (-5535 4085);
PAINT MONO (-5535 4085);
FORCEPROP 0 LASTPIN (-5525 4925) $PN CE64
J 2
(-5535 4935);
DISPLAY 0.489362 (-5535 4935);
PAINT MONO (-5535 4935);
FORCEPROP 0 LASTPIN (-5525 4825) $PN CL64
J 2
(-5535 4835);
DISPLAY 0.489362 (-5535 4835);
PAINT MONO (-5535 4835);
FORCEPROP 0 LASTPIN (-5525 4725) $PN CU64
J 2
(-5535 4735);
DISPLAY 0.489362 (-5535 4735);
PAINT MONO (-5535 4735);
FORCEPROP 0 LASTPIN (-5525 4625) $PN DC64
J 2
(-5535 4635);
DISPLAY 0.489362 (-5535 4635);
PAINT MONO (-5535 4635);
FORCEPROP 0 LASTPIN (-5525 4525) $PN BW62
J 2
(-5535 4535);
DISPLAY 0.489362 (-5535 4535);
PAINT MONO (-5535 4535);
FORCEPROP 0 LASTPIN (-5525 4425) $PN CE62
J 2
(-5535 4435);
DISPLAY 0.489362 (-5535 4435);
PAINT MONO (-5535 4435);
FORCEPROP 0 LASTPIN (-5525 4325) $PN CL62
J 2
(-5535 4335);
DISPLAY 0.489362 (-5535 4335);
PAINT MONO (-5535 4335);
FORCEPROP 0 LASTPIN (-5525 4225) $PN CU62
J 2
(-5535 4235);
DISPLAY 0.489362 (-5535 4235);
PAINT MONO (-5535 4235);
FORCEPROP 0 LASTPIN (-5525 4125) $PN DC62
J 2
(-5535 4135);
DISPLAY 0.489362 (-5535 4135);
PAINT MONO (-5535 4135);
FORCEPROP 0 LASTPIN (-5525 4025) $PN BW64
J 2
(-5535 4035);
DISPLAY 0.489362 (-5535 4035);
PAINT MONO (-5535 4035);
FORCEPROP 0 LASTPIN (-5525 2275) $PN BL64
J 2
(-5535 2285);
DISPLAY 0.489362 (-5535 2285);
PAINT MONO (-5535 2285);
FORCEPROP 0 LASTPIN (-5525 1225) $PN BF62
J 2
(-5535 1235);
DISPLAY 0.489362 (-5535 1235);
PAINT MONO (-5535 1235);
FORCEPROP 2 LAST PART_TYPE SMLF
J 0
(-5375 6375);
DISPLAY 1.021277 (-5375 6375);
FORCEPROP 1 LAST MATERIAL IO
J 0
(-5370 6207);
DISPLAY 0.489362 (-5370 6207);
PAINT SKYBLUE (-5370 6207);
FORCEPROP 2 LAST VALUE SOCKET6096_13568-001
J 0
(-5375 6275);
DISPLAY 0.489362 (-5375 6275);
PAINT SKYBLUE (-5375 6275);
FORCEPROP 2 LAST CDS_LIB pure_quanta
J 0
(-4725 3625);
DISPLAY INVISIBLE (-4725 3625);
FORCEPROP 1 LAST NEEDS_NO_SIZE TRUE
J 0
(-4725 3625);
DISPLAY 0.723404 (-4725 3625);
PAINT GREEN (-4725 3625);
DISPLAY INVISIBLE (-4725 3625);
FORCEPROP 1 LAST CDS_LMAN_SYM_OUTLINE -650,2550,650,-2550
J 0
(-4725 3625);
DISPLAY 0.468085 (-4725 3625);
PAINT GREEN (-4725 3625);
DISPLAY INVISIBLE (-4725 3625);
FORCEPROP 1 LAST PATH I159
J 0
(-4725 3625);
DISPLAY 0.723404 (-4725 3625);
PAINT GREEN (-4725 3625);
DISPLAY INVISIBLE (-4725 3625);
FORCEPROP 1 LAST PART_NUMBER DGA^6000030
J 0
(-5370 6334);
DISPLAY 0.489362 (-5370 6334);
PAINT SKYBLUE (-5370 6334);
DISPLAY INVISIBLE (-5370 6334);
FORCEADD OFFPAGE..3
(-2725 6050);
FORCEPROP 2 LAST $XR0 99 
J 0
(-2511 6050);
DISPLAY 0.638298 (-2511 6050);
PAINT MONO (-2511 6050);
FORCEPROP 2 LAST CDS_LIB mstr_standard
J 0
(-2725 6050);
DISPLAY 0.723404 (-2725 6050);
PAINT MONO (-2725 6050);
DISPLAY INVISIBLE (-2725 6050);
FORCEPROP 1 LAST OFFPAGE TRUE
J 0
(-2400 5925);
DISPLAY 0.872340 (-2400 5925);
PAINT GREEN (-2400 5925);
DISPLAY INVISIBLE (-2400 5925);
FORCEPROP 1 LAST COMMENT_BODY TRUE
J 0
(-2775 5950);
DISPLAY 0.872340 (-2775 5950);
PAINT GREEN (-2775 5950);
DISPLAY INVISIBLE (-2775 5950);
FORCEPROP 2 LAST PATH I160
J 0
(-2500 6100);
DISPLAY 1.021277 (-2500 6100);
DISPLAY INVISIBLE (-2500 6100);
FORCEADD OFFPAGE..3
(-2725 4250);
FORCEPROP 2 LAST $XR0 99 
J 0
(-2511 4250);
DISPLAY 0.638298 (-2511 4250);
PAINT MONO (-2511 4250);
FORCEPROP 2 LAST CDS_LIB mstr_standard
J 0
(-2725 4250);
DISPLAY 0.723404 (-2725 4250);
PAINT MONO (-2725 4250);
DISPLAY INVISIBLE (-2725 4250);
FORCEPROP 1 LAST OFFPAGE TRUE
J 0
(-2400 4125);
DISPLAY 0.872340 (-2400 4125);
PAINT GREEN (-2400 4125);
DISPLAY INVISIBLE (-2400 4125);
FORCEPROP 1 LAST COMMENT_BODY TRUE
J 0
(-2775 4150);
DISPLAY 0.872340 (-2775 4150);
PAINT GREEN (-2775 4150);
DISPLAY INVISIBLE (-2775 4150);
FORCEPROP 2 LAST PATH I161
J 0
(-2500 4300);
DISPLAY 1.021277 (-2500 4300);
DISPLAY INVISIBLE (-2500 4300);
FORCEADD TAP..1
(-3450 5925);
FORCEPROP 3 LASTPIN (-3500 5925) SIG_NAME M_B_CPU1_SA_DQ<2>
J 0
(-3490 5935);
DISPLAY 0.659574 (-3490 5935);
PAINT MONO (-3490 5935);
DISPLAY INVISIBLE (-3490 5935);
FORCEPROP 1 LASTPIN (-3500 5925) BN 2
J 0
(-3512 5933);
DISPLAY 0.489362 (-3512 5933);
PAINT GREEN (-3512 5933);
FORCEPROP 2 LAST CDS_LIB mstr_standard
J 0
(-3450 5925);
DISPLAY 0.723404 (-3450 5925);
PAINT MONO (-3450 5925);
DISPLAY INVISIBLE (-3450 5925);
FORCEPROP 1 LAST BODY_TYPE PLUMBING
J 0
(-3450 5975);
DISPLAY 0.872340 (-3450 5975);
PAINT GREEN (-3450 5975);
DISPLAY INVISIBLE (-3450 5975);
FORCEPROP 1 LAST HDL_TAP TRUE
J 0
(-3125 5800);
DISPLAY 0.872340 (-3125 5800);
DISPLAY INVISIBLE (-3125 5800);
FORCEPROP 1 LAST PATH I162
J 0
(-3452 5925);
DISPLAY 0.872340 (-3452 5925);
PAINT GREEN (-3452 5925);
DISPLAY INVISIBLE (-3452 5925);
FORCEADD TAP..1
(-3450 5975);
FORCEPROP 3 LASTPIN (-3500 5975) SIG_NAME M_B_CPU1_SA_DQ<1>
J 0
(-3490 5985);
DISPLAY 0.659574 (-3490 5985);
PAINT MONO (-3490 5985);
DISPLAY INVISIBLE (-3490 5985);
FORCEPROP 1 LASTPIN (-3500 5975) BN 1
J 0
(-3512 5983);
DISPLAY 0.489362 (-3512 5983);
PAINT GREEN (-3512 5983);
FORCEPROP 2 LAST CDS_LIB mstr_standard
J 0
(-3450 5975);
DISPLAY 0.723404 (-3450 5975);
PAINT MONO (-3450 5975);
DISPLAY INVISIBLE (-3450 5975);
FORCEPROP 1 LAST BODY_TYPE PLUMBING
J 0
(-3450 6025);
DISPLAY 0.872340 (-3450 6025);
PAINT GREEN (-3450 6025);
DISPLAY INVISIBLE (-3450 6025);
FORCEPROP 1 LAST HDL_TAP TRUE
J 0
(-3125 5850);
DISPLAY 0.872340 (-3125 5850);
DISPLAY INVISIBLE (-3125 5850);
FORCEPROP 1 LAST PATH I163
J 0
(-3452 5975);
DISPLAY 0.872340 (-3452 5975);
PAINT GREEN (-3452 5975);
DISPLAY INVISIBLE (-3452 5975);
FORCEADD TAP..1
(-3450 6025);
FORCEPROP 3 LASTPIN (-3500 6025) SIG_NAME M_B_CPU1_SA_DQ<0>
J 0
(-3490 6035);
DISPLAY 0.659574 (-3490 6035);
PAINT MONO (-3490 6035);
DISPLAY INVISIBLE (-3490 6035);
FORCEPROP 1 LASTPIN (-3500 6025) BN 0
J 0
(-3512 6033);
DISPLAY 0.489362 (-3512 6033);
PAINT GREEN (-3512 6033);
FORCEPROP 2 LAST CDS_LIB mstr_standard
J 0
(-3450 6025);
DISPLAY 0.723404 (-3450 6025);
PAINT MONO (-3450 6025);
DISPLAY INVISIBLE (-3450 6025);
FORCEPROP 1 LAST BODY_TYPE PLUMBING
J 0
(-3450 6075);
DISPLAY 0.872340 (-3450 6075);
PAINT GREEN (-3450 6075);
DISPLAY INVISIBLE (-3450 6075);
FORCEPROP 1 LAST HDL_TAP TRUE
J 0
(-3125 5900);
DISPLAY 0.872340 (-3125 5900);
DISPLAY INVISIBLE (-3125 5900);
FORCEPROP 1 LAST PATH I164
J 0
(-3452 6025);
DISPLAY 0.872340 (-3452 6025);
PAINT GREEN (-3452 6025);
DISPLAY INVISIBLE (-3452 6025);
FORCEADD TAP..1
(-3450 5825);
FORCEPROP 3 LASTPIN (-3500 5825) SIG_NAME M_B_CPU1_SA_DQ<4>
J 0
(-3490 5835);
DISPLAY 0.659574 (-3490 5835);
PAINT MONO (-3490 5835);
DISPLAY INVISIBLE (-3490 5835);
FORCEPROP 1 LASTPIN (-3500 5825) BN 4
J 0
(-3512 5833);
DISPLAY 0.489362 (-3512 5833);
PAINT GREEN (-3512 5833);
FORCEPROP 2 LAST CDS_LIB mstr_standard
J 0
(-3450 5825);
DISPLAY 0.723404 (-3450 5825);
PAINT MONO (-3450 5825);
DISPLAY INVISIBLE (-3450 5825);
FORCEPROP 1 LAST BODY_TYPE PLUMBING
J 0
(-3450 5875);
DISPLAY 0.872340 (-3450 5875);
PAINT GREEN (-3450 5875);
DISPLAY INVISIBLE (-3450 5875);
FORCEPROP 1 LAST HDL_TAP TRUE
J 0
(-3125 5700);
DISPLAY 0.872340 (-3125 5700);
DISPLAY INVISIBLE (-3125 5700);
FORCEPROP 1 LAST PATH I165
J 0
(-3452 5825);
DISPLAY 0.872340 (-3452 5825);
PAINT GREEN (-3452 5825);
DISPLAY INVISIBLE (-3452 5825);
FORCEADD TAP..1
(-3450 5875);
FORCEPROP 3 LASTPIN (-3500 5875) SIG_NAME M_B_CPU1_SA_DQ<3>
J 0
(-3490 5885);
DISPLAY 0.659574 (-3490 5885);
PAINT MONO (-3490 5885);
DISPLAY INVISIBLE (-3490 5885);
FORCEPROP 1 LASTPIN (-3500 5875) BN 3
J 0
(-3512 5883);
DISPLAY 0.489362 (-3512 5883);
PAINT GREEN (-3512 5883);
FORCEPROP 2 LAST CDS_LIB mstr_standard
J 0
(-3450 5875);
DISPLAY 0.723404 (-3450 5875);
PAINT MONO (-3450 5875);
DISPLAY INVISIBLE (-3450 5875);
FORCEPROP 1 LAST BODY_TYPE PLUMBING
J 0
(-3450 5925);
DISPLAY 0.872340 (-3450 5925);
PAINT GREEN (-3450 5925);
DISPLAY INVISIBLE (-3450 5925);
FORCEPROP 1 LAST HDL_TAP TRUE
J 0
(-3125 5750);
DISPLAY 0.872340 (-3125 5750);
DISPLAY INVISIBLE (-3125 5750);
FORCEPROP 1 LAST PATH I166
J 0
(-3452 5875);
DISPLAY 0.872340 (-3452 5875);
PAINT GREEN (-3452 5875);
DISPLAY INVISIBLE (-3452 5875);
FORCEADD TAP..1
(-3450 5775);
FORCEPROP 3 LASTPIN (-3500 5775) SIG_NAME M_B_CPU1_SA_DQ<5>
J 0
(-3490 5785);
DISPLAY 0.659574 (-3490 5785);
PAINT MONO (-3490 5785);
DISPLAY INVISIBLE (-3490 5785);
FORCEPROP 1 LASTPIN (-3500 5775) BN 5
J 0
(-3512 5783);
DISPLAY 0.489362 (-3512 5783);
PAINT GREEN (-3512 5783);
FORCEPROP 2 LAST CDS_LIB mstr_standard
J 0
(-3450 5775);
DISPLAY 0.723404 (-3450 5775);
PAINT MONO (-3450 5775);
DISPLAY INVISIBLE (-3450 5775);
FORCEPROP 1 LAST BODY_TYPE PLUMBING
J 0
(-3450 5825);
DISPLAY 0.872340 (-3450 5825);
PAINT GREEN (-3450 5825);
DISPLAY INVISIBLE (-3450 5825);
FORCEPROP 1 LAST HDL_TAP TRUE
J 0
(-3125 5650);
DISPLAY 0.872340 (-3125 5650);
DISPLAY INVISIBLE (-3125 5650);
FORCEPROP 1 LAST PATH I167
J 0
(-3452 5775);
DISPLAY 0.872340 (-3452 5775);
PAINT GREEN (-3452 5775);
DISPLAY INVISIBLE (-3452 5775);
FORCEADD TAP..1
(-3450 5725);
FORCEPROP 3 LASTPIN (-3500 5725) SIG_NAME M_B_CPU1_SA_DQ<6>
J 0
(-3490 5735);
DISPLAY 0.659574 (-3490 5735);
PAINT MONO (-3490 5735);
DISPLAY INVISIBLE (-3490 5735);
FORCEPROP 1 LASTPIN (-3500 5725) BN 6
J 0
(-3512 5733);
DISPLAY 0.489362 (-3512 5733);
PAINT GREEN (-3512 5733);
FORCEPROP 2 LAST CDS_LIB mstr_standard
J 0
(-3450 5725);
DISPLAY 0.723404 (-3450 5725);
PAINT MONO (-3450 5725);
DISPLAY INVISIBLE (-3450 5725);
FORCEPROP 1 LAST BODY_TYPE PLUMBING
J 0
(-3450 5775);
DISPLAY 0.872340 (-3450 5775);
PAINT GREEN (-3450 5775);
DISPLAY INVISIBLE (-3450 5775);
FORCEPROP 1 LAST HDL_TAP TRUE
J 0
(-3125 5600);
DISPLAY 0.872340 (-3125 5600);
DISPLAY INVISIBLE (-3125 5600);
FORCEPROP 1 LAST PATH I168
J 0
(-3452 5725);
DISPLAY 0.872340 (-3452 5725);
PAINT GREEN (-3452 5725);
DISPLAY INVISIBLE (-3452 5725);
FORCEADD TAP..1
(-3450 5675);
FORCEPROP 3 LASTPIN (-3500 5675) SIG_NAME M_B_CPU1_SA_DQ<7>
J 0
(-3490 5685);
DISPLAY 0.659574 (-3490 5685);
PAINT MONO (-3490 5685);
DISPLAY INVISIBLE (-3490 5685);
FORCEPROP 1 LASTPIN (-3500 5675) BN 7
J 0
(-3512 5683);
DISPLAY 0.489362 (-3512 5683);
PAINT GREEN (-3512 5683);
FORCEPROP 2 LAST CDS_LIB mstr_standard
J 0
(-3450 5675);
DISPLAY 0.723404 (-3450 5675);
PAINT MONO (-3450 5675);
DISPLAY INVISIBLE (-3450 5675);
FORCEPROP 1 LAST BODY_TYPE PLUMBING
J 0
(-3450 5725);
DISPLAY 0.872340 (-3450 5725);
PAINT GREEN (-3450 5725);
DISPLAY INVISIBLE (-3450 5725);
FORCEPROP 1 LAST HDL_TAP TRUE
J 0
(-3125 5550);
DISPLAY 0.872340 (-3125 5550);
DISPLAY INVISIBLE (-3125 5550);
FORCEPROP 1 LAST PATH I169
J 0
(-3452 5675);
DISPLAY 0.872340 (-3452 5675);
PAINT GREEN (-3452 5675);
DISPLAY INVISIBLE (-3452 5675);
FORCEADD TAP..1
(-3450 5575);
FORCEPROP 3 LASTPIN (-3500 5575) SIG_NAME M_B_CPU1_SA_DQ<8>
J 0
(-3490 5585);
DISPLAY 0.659574 (-3490 5585);
PAINT MONO (-3490 5585);
DISPLAY INVISIBLE (-3490 5585);
FORCEPROP 1 LASTPIN (-3500 5575) BN 8
J 0
(-3512 5583);
DISPLAY 0.489362 (-3512 5583);
PAINT GREEN (-3512 5583);
FORCEPROP 2 LAST CDS_LIB mstr_standard
J 0
(-3450 5575);
DISPLAY 0.723404 (-3450 5575);
PAINT MONO (-3450 5575);
DISPLAY INVISIBLE (-3450 5575);
FORCEPROP 1 LAST BODY_TYPE PLUMBING
J 0
(-3450 5625);
DISPLAY 0.872340 (-3450 5625);
PAINT GREEN (-3450 5625);
DISPLAY INVISIBLE (-3450 5625);
FORCEPROP 1 LAST HDL_TAP TRUE
J 0
(-3125 5450);
DISPLAY 0.872340 (-3125 5450);
DISPLAY INVISIBLE (-3125 5450);
FORCEPROP 1 LAST PATH I170
J 0
(-3452 5575);
DISPLAY 0.872340 (-3452 5575);
PAINT GREEN (-3452 5575);
DISPLAY INVISIBLE (-3452 5575);
FORCEADD TAP..1
(-3450 5425);
FORCEPROP 3 LASTPIN (-3500 5425) SIG_NAME M_B_CPU1_SA_DQ<11>
J 0
(-3490 5435);
DISPLAY 0.659574 (-3490 5435);
PAINT MONO (-3490 5435);
DISPLAY INVISIBLE (-3490 5435);
FORCEPROP 1 LASTPIN (-3500 5425) BN 11
J 0
(-3512 5433);
DISPLAY 0.489362 (-3512 5433);
PAINT GREEN (-3512 5433);
FORCEPROP 2 LAST CDS_LIB mstr_standard
J 0
(-3450 5425);
DISPLAY 0.723404 (-3450 5425);
PAINT MONO (-3450 5425);
DISPLAY INVISIBLE (-3450 5425);
FORCEPROP 1 LAST BODY_TYPE PLUMBING
J 0
(-3450 5475);
DISPLAY 0.872340 (-3450 5475);
PAINT GREEN (-3450 5475);
DISPLAY INVISIBLE (-3450 5475);
FORCEPROP 1 LAST HDL_TAP TRUE
J 0
(-3125 5300);
DISPLAY 0.872340 (-3125 5300);
DISPLAY INVISIBLE (-3125 5300);
FORCEPROP 1 LAST PATH I171
J 0
(-3452 5425);
DISPLAY 0.872340 (-3452 5425);
PAINT GREEN (-3452 5425);
DISPLAY INVISIBLE (-3452 5425);
FORCEADD TAP..1
(-3450 5475);
FORCEPROP 3 LASTPIN (-3500 5475) SIG_NAME M_B_CPU1_SA_DQ<10>
J 0
(-3490 5485);
DISPLAY 0.659574 (-3490 5485);
PAINT MONO (-3490 5485);
DISPLAY INVISIBLE (-3490 5485);
FORCEPROP 1 LASTPIN (-3500 5475) BN 10
J 0
(-3512 5483);
DISPLAY 0.489362 (-3512 5483);
PAINT GREEN (-3512 5483);
FORCEPROP 2 LAST CDS_LIB mstr_standard
J 0
(-3450 5475);
DISPLAY 0.723404 (-3450 5475);
PAINT MONO (-3450 5475);
DISPLAY INVISIBLE (-3450 5475);
FORCEPROP 1 LAST BODY_TYPE PLUMBING
J 0
(-3450 5525);
DISPLAY 0.872340 (-3450 5525);
PAINT GREEN (-3450 5525);
DISPLAY INVISIBLE (-3450 5525);
FORCEPROP 1 LAST HDL_TAP TRUE
J 0
(-3125 5350);
DISPLAY 0.872340 (-3125 5350);
DISPLAY INVISIBLE (-3125 5350);
FORCEPROP 1 LAST PATH I172
J 0
(-3452 5475);
DISPLAY 0.872340 (-3452 5475);
PAINT GREEN (-3452 5475);
DISPLAY INVISIBLE (-3452 5475);
FORCEADD TAP..1
(-3450 5525);
FORCEPROP 3 LASTPIN (-3500 5525) SIG_NAME M_B_CPU1_SA_DQ<9>
J 0
(-3490 5535);
DISPLAY 0.659574 (-3490 5535);
PAINT MONO (-3490 5535);
DISPLAY INVISIBLE (-3490 5535);
FORCEPROP 1 LASTPIN (-3500 5525) BN 9
J 0
(-3512 5533);
DISPLAY 0.489362 (-3512 5533);
PAINT GREEN (-3512 5533);
FORCEPROP 2 LAST CDS_LIB mstr_standard
J 0
(-3450 5525);
DISPLAY 0.723404 (-3450 5525);
PAINT MONO (-3450 5525);
DISPLAY INVISIBLE (-3450 5525);
FORCEPROP 1 LAST BODY_TYPE PLUMBING
J 0
(-3450 5575);
DISPLAY 0.872340 (-3450 5575);
PAINT GREEN (-3450 5575);
DISPLAY INVISIBLE (-3450 5575);
FORCEPROP 1 LAST HDL_TAP TRUE
J 0
(-3125 5400);
DISPLAY 0.872340 (-3125 5400);
DISPLAY INVISIBLE (-3125 5400);
FORCEPROP 1 LAST PATH I173
J 0
(-3452 5525);
DISPLAY 0.872340 (-3452 5525);
PAINT GREEN (-3452 5525);
DISPLAY INVISIBLE (-3452 5525);
FORCEADD TAP..1
(-3450 5375);
FORCEPROP 3 LASTPIN (-3500 5375) SIG_NAME M_B_CPU1_SA_DQ<12>
J 0
(-3490 5385);
DISPLAY 0.659574 (-3490 5385);
PAINT MONO (-3490 5385);
DISPLAY INVISIBLE (-3490 5385);
FORCEPROP 1 LASTPIN (-3500 5375) BN 12
J 0
(-3512 5383);
DISPLAY 0.489362 (-3512 5383);
PAINT GREEN (-3512 5383);
FORCEPROP 2 LAST CDS_LIB mstr_standard
J 0
(-3450 5375);
DISPLAY 0.723404 (-3450 5375);
PAINT MONO (-3450 5375);
DISPLAY INVISIBLE (-3450 5375);
FORCEPROP 1 LAST BODY_TYPE PLUMBING
J 0
(-3450 5425);
DISPLAY 0.872340 (-3450 5425);
PAINT GREEN (-3450 5425);
DISPLAY INVISIBLE (-3450 5425);
FORCEPROP 1 LAST HDL_TAP TRUE
J 0
(-3125 5250);
DISPLAY 0.872340 (-3125 5250);
DISPLAY INVISIBLE (-3125 5250);
FORCEPROP 1 LAST PATH I174
J 0
(-3452 5375);
DISPLAY 0.872340 (-3452 5375);
PAINT GREEN (-3452 5375);
DISPLAY INVISIBLE (-3452 5375);
FORCEADD TAP..1
(-3450 5325);
FORCEPROP 3 LASTPIN (-3500 5325) SIG_NAME M_B_CPU1_SA_DQ<13>
J 0
(-3490 5335);
DISPLAY 0.659574 (-3490 5335);
PAINT MONO (-3490 5335);
DISPLAY INVISIBLE (-3490 5335);
FORCEPROP 1 LASTPIN (-3500 5325) BN 13
J 0
(-3512 5333);
DISPLAY 0.489362 (-3512 5333);
PAINT GREEN (-3512 5333);
FORCEPROP 2 LAST CDS_LIB mstr_standard
J 0
(-3450 5325);
DISPLAY 0.723404 (-3450 5325);
PAINT MONO (-3450 5325);
DISPLAY INVISIBLE (-3450 5325);
FORCEPROP 1 LAST BODY_TYPE PLUMBING
J 0
(-3450 5375);
DISPLAY 0.872340 (-3450 5375);
PAINT GREEN (-3450 5375);
DISPLAY INVISIBLE (-3450 5375);
FORCEPROP 1 LAST HDL_TAP TRUE
J 0
(-3125 5200);
DISPLAY 0.872340 (-3125 5200);
DISPLAY INVISIBLE (-3125 5200);
FORCEPROP 1 LAST PATH I175
J 0
(-3452 5325);
DISPLAY 0.872340 (-3452 5325);
PAINT GREEN (-3452 5325);
DISPLAY INVISIBLE (-3452 5325);
FORCEADD TAP..1
(-3450 5275);
FORCEPROP 3 LASTPIN (-3500 5275) SIG_NAME M_B_CPU1_SA_DQ<14>
J 0
(-3490 5285);
DISPLAY 0.659574 (-3490 5285);
PAINT MONO (-3490 5285);
DISPLAY INVISIBLE (-3490 5285);
FORCEPROP 1 LASTPIN (-3500 5275) BN 14
J 0
(-3512 5283);
DISPLAY 0.489362 (-3512 5283);
PAINT GREEN (-3512 5283);
FORCEPROP 2 LAST CDS_LIB mstr_standard
J 0
(-3450 5275);
DISPLAY 0.723404 (-3450 5275);
PAINT MONO (-3450 5275);
DISPLAY INVISIBLE (-3450 5275);
FORCEPROP 1 LAST BODY_TYPE PLUMBING
J 0
(-3450 5325);
DISPLAY 0.872340 (-3450 5325);
PAINT GREEN (-3450 5325);
DISPLAY INVISIBLE (-3450 5325);
FORCEPROP 1 LAST HDL_TAP TRUE
J 0
(-3125 5150);
DISPLAY 0.872340 (-3125 5150);
DISPLAY INVISIBLE (-3125 5150);
FORCEPROP 1 LAST PATH I176
J 0
(-3452 5275);
DISPLAY 0.872340 (-3452 5275);
PAINT GREEN (-3452 5275);
DISPLAY INVISIBLE (-3452 5275);
FORCEADD TAP..1
(-3450 5225);
FORCEPROP 3 LASTPIN (-3500 5225) SIG_NAME M_B_CPU1_SA_DQ<15>
J 0
(-3490 5235);
DISPLAY 0.659574 (-3490 5235);
PAINT MONO (-3490 5235);
DISPLAY INVISIBLE (-3490 5235);
FORCEPROP 1 LASTPIN (-3500 5225) BN 15
J 0
(-3512 5233);
DISPLAY 0.489362 (-3512 5233);
PAINT GREEN (-3512 5233);
FORCEPROP 2 LAST CDS_LIB mstr_standard
J 0
(-3450 5225);
DISPLAY 0.723404 (-3450 5225);
PAINT MONO (-3450 5225);
DISPLAY INVISIBLE (-3450 5225);
FORCEPROP 1 LAST BODY_TYPE PLUMBING
J 0
(-3450 5275);
DISPLAY 0.872340 (-3450 5275);
PAINT GREEN (-3450 5275);
DISPLAY INVISIBLE (-3450 5275);
FORCEPROP 1 LAST HDL_TAP TRUE
J 0
(-3125 5100);
DISPLAY 0.872340 (-3125 5100);
DISPLAY INVISIBLE (-3125 5100);
FORCEPROP 1 LAST PATH I177
J 0
(-3452 5225);
DISPLAY 0.872340 (-3452 5225);
PAINT GREEN (-3452 5225);
DISPLAY INVISIBLE (-3452 5225);
FORCEADD TAP..1
(-3450 5125);
FORCEPROP 3 LASTPIN (-3500 5125) SIG_NAME M_B_CPU1_SA_DQ<16>
J 0
(-3490 5135);
DISPLAY 0.659574 (-3490 5135);
PAINT MONO (-3490 5135);
DISPLAY INVISIBLE (-3490 5135);
FORCEPROP 1 LASTPIN (-3500 5125) BN 16
J 0
(-3512 5133);
DISPLAY 0.489362 (-3512 5133);
PAINT GREEN (-3512 5133);
FORCEPROP 2 LAST CDS_LIB mstr_standard
J 0
(-3450 5125);
DISPLAY 0.723404 (-3450 5125);
PAINT MONO (-3450 5125);
DISPLAY INVISIBLE (-3450 5125);
FORCEPROP 1 LAST BODY_TYPE PLUMBING
J 0
(-3450 5175);
DISPLAY 0.872340 (-3450 5175);
PAINT GREEN (-3450 5175);
DISPLAY INVISIBLE (-3450 5175);
FORCEPROP 1 LAST HDL_TAP TRUE
J 0
(-3125 5000);
DISPLAY 0.872340 (-3125 5000);
DISPLAY INVISIBLE (-3125 5000);
FORCEPROP 1 LAST PATH I178
J 0
(-3452 5125);
DISPLAY 0.872340 (-3452 5125);
PAINT GREEN (-3452 5125);
DISPLAY INVISIBLE (-3452 5125);
FORCEADD TAP..1
(-3450 5075);
FORCEPROP 3 LASTPIN (-3500 5075) SIG_NAME M_B_CPU1_SA_DQ<17>
J 0
(-3490 5085);
DISPLAY 0.659574 (-3490 5085);
PAINT MONO (-3490 5085);
DISPLAY INVISIBLE (-3490 5085);
FORCEPROP 1 LASTPIN (-3500 5075) BN 17
J 0
(-3512 5083);
DISPLAY 0.489362 (-3512 5083);
PAINT GREEN (-3512 5083);
FORCEPROP 2 LAST CDS_LIB mstr_standard
J 0
(-3450 5075);
DISPLAY 0.723404 (-3450 5075);
PAINT MONO (-3450 5075);
DISPLAY INVISIBLE (-3450 5075);
FORCEPROP 1 LAST BODY_TYPE PLUMBING
J 0
(-3450 5125);
DISPLAY 0.872340 (-3450 5125);
PAINT GREEN (-3450 5125);
DISPLAY INVISIBLE (-3450 5125);
FORCEPROP 1 LAST HDL_TAP TRUE
J 0
(-3125 4950);
DISPLAY 0.872340 (-3125 4950);
DISPLAY INVISIBLE (-3125 4950);
FORCEPROP 1 LAST PATH I179
J 0
(-3452 5075);
DISPLAY 0.872340 (-3452 5075);
PAINT GREEN (-3452 5075);
DISPLAY INVISIBLE (-3452 5075);
FORCEADD TAP..1
(-3450 5025);
FORCEPROP 3 LASTPIN (-3500 5025) SIG_NAME M_B_CPU1_SA_DQ<18>
J 0
(-3490 5035);
DISPLAY 0.659574 (-3490 5035);
PAINT MONO (-3490 5035);
DISPLAY INVISIBLE (-3490 5035);
FORCEPROP 1 LASTPIN (-3500 5025) BN 18
J 0
(-3512 5033);
DISPLAY 0.489362 (-3512 5033);
PAINT GREEN (-3512 5033);
FORCEPROP 2 LAST CDS_LIB mstr_standard
J 0
(-3450 5025);
DISPLAY 0.723404 (-3450 5025);
PAINT MONO (-3450 5025);
DISPLAY INVISIBLE (-3450 5025);
FORCEPROP 1 LAST BODY_TYPE PLUMBING
J 0
(-3450 5075);
DISPLAY 0.872340 (-3450 5075);
PAINT GREEN (-3450 5075);
DISPLAY INVISIBLE (-3450 5075);
FORCEPROP 1 LAST HDL_TAP TRUE
J 0
(-3125 4900);
DISPLAY 0.872340 (-3125 4900);
DISPLAY INVISIBLE (-3125 4900);
FORCEPROP 1 LAST PATH I180
J 0
(-3452 5025);
DISPLAY 0.872340 (-3452 5025);
PAINT GREEN (-3452 5025);
DISPLAY INVISIBLE (-3452 5025);
FORCEADD TAP..1
(-3450 4925);
FORCEPROP 3 LASTPIN (-3500 4925) SIG_NAME M_B_CPU1_SA_DQ<20>
J 0
(-3490 4935);
DISPLAY 0.659574 (-3490 4935);
PAINT MONO (-3490 4935);
DISPLAY INVISIBLE (-3490 4935);
FORCEPROP 1 LASTPIN (-3500 4925) BN 20
J 0
(-3512 4933);
DISPLAY 0.489362 (-3512 4933);
PAINT GREEN (-3512 4933);
FORCEPROP 2 LAST CDS_LIB mstr_standard
J 0
(-3450 4925);
DISPLAY 0.723404 (-3450 4925);
PAINT MONO (-3450 4925);
DISPLAY INVISIBLE (-3450 4925);
FORCEPROP 1 LAST BODY_TYPE PLUMBING
J 0
(-3450 4975);
DISPLAY 0.872340 (-3450 4975);
PAINT GREEN (-3450 4975);
DISPLAY INVISIBLE (-3450 4975);
FORCEPROP 1 LAST HDL_TAP TRUE
J 0
(-3125 4800);
DISPLAY 0.872340 (-3125 4800);
DISPLAY INVISIBLE (-3125 4800);
FORCEPROP 1 LAST PATH I181
J 0
(-3452 4925);
DISPLAY 0.872340 (-3452 4925);
PAINT GREEN (-3452 4925);
DISPLAY INVISIBLE (-3452 4925);
FORCEADD TAP..1
(-3450 4975);
FORCEPROP 3 LASTPIN (-3500 4975) SIG_NAME M_B_CPU1_SA_DQ<19>
J 0
(-3490 4985);
DISPLAY 0.659574 (-3490 4985);
PAINT MONO (-3490 4985);
DISPLAY INVISIBLE (-3490 4985);
FORCEPROP 1 LASTPIN (-3500 4975) BN 19
J 0
(-3512 4983);
DISPLAY 0.489362 (-3512 4983);
PAINT GREEN (-3512 4983);
FORCEPROP 2 LAST CDS_LIB mstr_standard
J 0
(-3450 4975);
DISPLAY 0.723404 (-3450 4975);
PAINT MONO (-3450 4975);
DISPLAY INVISIBLE (-3450 4975);
FORCEPROP 1 LAST BODY_TYPE PLUMBING
J 0
(-3450 5025);
DISPLAY 0.872340 (-3450 5025);
PAINT GREEN (-3450 5025);
DISPLAY INVISIBLE (-3450 5025);
FORCEPROP 1 LAST HDL_TAP TRUE
J 0
(-3125 4850);
DISPLAY 0.872340 (-3125 4850);
DISPLAY INVISIBLE (-3125 4850);
FORCEPROP 1 LAST PATH I182
J 0
(-3452 4975);
DISPLAY 0.872340 (-3452 4975);
PAINT GREEN (-3452 4975);
DISPLAY INVISIBLE (-3452 4975);
FORCEADD TAP..1
(-3450 4875);
FORCEPROP 3 LASTPIN (-3500 4875) SIG_NAME M_B_CPU1_SA_DQ<21>
J 0
(-3490 4885);
DISPLAY 0.659574 (-3490 4885);
PAINT MONO (-3490 4885);
DISPLAY INVISIBLE (-3490 4885);
FORCEPROP 1 LASTPIN (-3500 4875) BN 21
J 0
(-3512 4883);
DISPLAY 0.489362 (-3512 4883);
PAINT GREEN (-3512 4883);
FORCEPROP 2 LAST CDS_LIB mstr_standard
J 0
(-3450 4875);
DISPLAY 0.723404 (-3450 4875);
PAINT MONO (-3450 4875);
DISPLAY INVISIBLE (-3450 4875);
FORCEPROP 1 LAST BODY_TYPE PLUMBING
J 0
(-3450 4925);
DISPLAY 0.872340 (-3450 4925);
PAINT GREEN (-3450 4925);
DISPLAY INVISIBLE (-3450 4925);
FORCEPROP 1 LAST HDL_TAP TRUE
J 0
(-3125 4750);
DISPLAY 0.872340 (-3125 4750);
DISPLAY INVISIBLE (-3125 4750);
FORCEPROP 1 LAST PATH I183
J 0
(-3452 4875);
DISPLAY 0.872340 (-3452 4875);
PAINT GREEN (-3452 4875);
DISPLAY INVISIBLE (-3452 4875);
FORCEADD TAP..1
(-3450 4825);
FORCEPROP 3 LASTPIN (-3500 4825) SIG_NAME M_B_CPU1_SA_DQ<22>
J 0
(-3490 4835);
DISPLAY 0.659574 (-3490 4835);
PAINT MONO (-3490 4835);
DISPLAY INVISIBLE (-3490 4835);
FORCEPROP 1 LASTPIN (-3500 4825) BN 22
J 0
(-3512 4833);
DISPLAY 0.489362 (-3512 4833);
PAINT GREEN (-3512 4833);
FORCEPROP 2 LAST CDS_LIB mstr_standard
J 0
(-3450 4825);
DISPLAY 0.723404 (-3450 4825);
PAINT MONO (-3450 4825);
DISPLAY INVISIBLE (-3450 4825);
FORCEPROP 1 LAST BODY_TYPE PLUMBING
J 0
(-3450 4875);
DISPLAY 0.872340 (-3450 4875);
PAINT GREEN (-3450 4875);
DISPLAY INVISIBLE (-3450 4875);
FORCEPROP 1 LAST HDL_TAP TRUE
J 0
(-3125 4700);
DISPLAY 0.872340 (-3125 4700);
DISPLAY INVISIBLE (-3125 4700);
FORCEPROP 1 LAST PATH I184
J 0
(-3452 4825);
DISPLAY 0.872340 (-3452 4825);
PAINT GREEN (-3452 4825);
DISPLAY INVISIBLE (-3452 4825);
FORCEADD TAP..1
(-3450 4775);
FORCEPROP 3 LASTPIN (-3500 4775) SIG_NAME M_B_CPU1_SA_DQ<23>
J 0
(-3490 4785);
DISPLAY 0.659574 (-3490 4785);
PAINT MONO (-3490 4785);
DISPLAY INVISIBLE (-3490 4785);
FORCEPROP 1 LASTPIN (-3500 4775) BN 23
J 0
(-3512 4783);
DISPLAY 0.489362 (-3512 4783);
PAINT GREEN (-3512 4783);
FORCEPROP 2 LAST CDS_LIB mstr_standard
J 0
(-3450 4775);
DISPLAY 0.723404 (-3450 4775);
PAINT MONO (-3450 4775);
DISPLAY INVISIBLE (-3450 4775);
FORCEPROP 1 LAST BODY_TYPE PLUMBING
J 0
(-3450 4825);
DISPLAY 0.872340 (-3450 4825);
PAINT GREEN (-3450 4825);
DISPLAY INVISIBLE (-3450 4825);
FORCEPROP 1 LAST HDL_TAP TRUE
J 0
(-3125 4650);
DISPLAY 0.872340 (-3125 4650);
DISPLAY INVISIBLE (-3125 4650);
FORCEPROP 1 LAST PATH I185
J 0
(-3452 4775);
DISPLAY 0.872340 (-3452 4775);
PAINT GREEN (-3452 4775);
DISPLAY INVISIBLE (-3452 4775);
FORCEADD TAP..1
(-3450 4675);
FORCEPROP 3 LASTPIN (-3500 4675) SIG_NAME M_B_CPU1_SA_DQ<24>
J 0
(-3490 4685);
DISPLAY 0.659574 (-3490 4685);
PAINT MONO (-3490 4685);
DISPLAY INVISIBLE (-3490 4685);
FORCEPROP 1 LASTPIN (-3500 4675) BN 24
J 0
(-3512 4683);
DISPLAY 0.489362 (-3512 4683);
PAINT GREEN (-3512 4683);
FORCEPROP 2 LAST CDS_LIB mstr_standard
J 0
(-3450 4675);
DISPLAY 0.723404 (-3450 4675);
PAINT MONO (-3450 4675);
DISPLAY INVISIBLE (-3450 4675);
FORCEPROP 1 LAST BODY_TYPE PLUMBING
J 0
(-3450 4725);
DISPLAY 0.872340 (-3450 4725);
PAINT GREEN (-3450 4725);
DISPLAY INVISIBLE (-3450 4725);
FORCEPROP 1 LAST HDL_TAP TRUE
J 0
(-3125 4550);
DISPLAY 0.872340 (-3125 4550);
DISPLAY INVISIBLE (-3125 4550);
FORCEPROP 1 LAST PATH I186
J 0
(-3452 4675);
DISPLAY 0.872340 (-3452 4675);
PAINT GREEN (-3452 4675);
DISPLAY INVISIBLE (-3452 4675);
FORCEADD TAP..1
(-3450 4625);
FORCEPROP 3 LASTPIN (-3500 4625) SIG_NAME M_B_CPU1_SA_DQ<25>
J 0
(-3490 4635);
DISPLAY 0.659574 (-3490 4635);
PAINT MONO (-3490 4635);
DISPLAY INVISIBLE (-3490 4635);
FORCEPROP 1 LASTPIN (-3500 4625) BN 25
J 0
(-3512 4633);
DISPLAY 0.489362 (-3512 4633);
PAINT GREEN (-3512 4633);
FORCEPROP 2 LAST CDS_LIB mstr_standard
J 0
(-3450 4625);
DISPLAY 0.723404 (-3450 4625);
PAINT MONO (-3450 4625);
DISPLAY INVISIBLE (-3450 4625);
FORCEPROP 1 LAST BODY_TYPE PLUMBING
J 0
(-3450 4675);
DISPLAY 0.872340 (-3450 4675);
PAINT GREEN (-3450 4675);
DISPLAY INVISIBLE (-3450 4675);
FORCEPROP 1 LAST HDL_TAP TRUE
J 0
(-3125 4500);
DISPLAY 0.872340 (-3125 4500);
DISPLAY INVISIBLE (-3125 4500);
FORCEPROP 1 LAST PATH I187
J 0
(-3452 4625);
DISPLAY 0.872340 (-3452 4625);
PAINT GREEN (-3452 4625);
DISPLAY INVISIBLE (-3452 4625);
FORCEADD TAP..1
(-3450 4575);
FORCEPROP 3 LASTPIN (-3500 4575) SIG_NAME M_B_CPU1_SA_DQ<26>
J 0
(-3490 4585);
DISPLAY 0.659574 (-3490 4585);
PAINT MONO (-3490 4585);
DISPLAY INVISIBLE (-3490 4585);
FORCEPROP 1 LASTPIN (-3500 4575) BN 26
J 0
(-3512 4583);
DISPLAY 0.489362 (-3512 4583);
PAINT GREEN (-3512 4583);
FORCEPROP 2 LAST CDS_LIB mstr_standard
J 0
(-3450 4575);
DISPLAY 0.723404 (-3450 4575);
PAINT MONO (-3450 4575);
DISPLAY INVISIBLE (-3450 4575);
FORCEPROP 1 LAST BODY_TYPE PLUMBING
J 0
(-3450 4625);
DISPLAY 0.872340 (-3450 4625);
PAINT GREEN (-3450 4625);
DISPLAY INVISIBLE (-3450 4625);
FORCEPROP 1 LAST HDL_TAP TRUE
J 0
(-3125 4450);
DISPLAY 0.872340 (-3125 4450);
DISPLAY INVISIBLE (-3125 4450);
FORCEPROP 1 LAST PATH I188
J 0
(-3452 4575);
DISPLAY 0.872340 (-3452 4575);
PAINT GREEN (-3452 4575);
DISPLAY INVISIBLE (-3452 4575);
FORCEADD TAP..1
(-3450 4525);
FORCEPROP 3 LASTPIN (-3500 4525) SIG_NAME M_B_CPU1_SA_DQ<27>
J 0
(-3490 4535);
DISPLAY 0.659574 (-3490 4535);
PAINT MONO (-3490 4535);
DISPLAY INVISIBLE (-3490 4535);
FORCEPROP 1 LASTPIN (-3500 4525) BN 27
J 0
(-3512 4533);
DISPLAY 0.489362 (-3512 4533);
PAINT GREEN (-3512 4533);
FORCEPROP 2 LAST CDS_LIB mstr_standard
J 0
(-3450 4525);
DISPLAY 0.723404 (-3450 4525);
PAINT MONO (-3450 4525);
DISPLAY INVISIBLE (-3450 4525);
FORCEPROP 1 LAST BODY_TYPE PLUMBING
J 0
(-3450 4575);
DISPLAY 0.872340 (-3450 4575);
PAINT GREEN (-3450 4575);
DISPLAY INVISIBLE (-3450 4575);
FORCEPROP 1 LAST HDL_TAP TRUE
J 0
(-3125 4400);
DISPLAY 0.872340 (-3125 4400);
DISPLAY INVISIBLE (-3125 4400);
FORCEPROP 1 LAST PATH I189
J 0
(-3452 4525);
DISPLAY 0.872340 (-3452 4525);
PAINT GREEN (-3452 4525);
DISPLAY INVISIBLE (-3452 4525);
FORCEADD TAP..1
(-3450 4425);
FORCEPROP 3 LASTPIN (-3500 4425) SIG_NAME M_B_CPU1_SA_DQ<29>
J 0
(-3490 4435);
DISPLAY 0.659574 (-3490 4435);
PAINT MONO (-3490 4435);
DISPLAY INVISIBLE (-3490 4435);
FORCEPROP 1 LASTPIN (-3500 4425) BN 29
J 0
(-3512 4433);
DISPLAY 0.489362 (-3512 4433);
PAINT GREEN (-3512 4433);
FORCEPROP 2 LAST CDS_LIB mstr_standard
J 0
(-3450 4425);
DISPLAY 0.723404 (-3450 4425);
PAINT MONO (-3450 4425);
DISPLAY INVISIBLE (-3450 4425);
FORCEPROP 1 LAST BODY_TYPE PLUMBING
J 0
(-3450 4475);
DISPLAY 0.872340 (-3450 4475);
PAINT GREEN (-3450 4475);
DISPLAY INVISIBLE (-3450 4475);
FORCEPROP 1 LAST HDL_TAP TRUE
J 0
(-3125 4300);
DISPLAY 0.872340 (-3125 4300);
DISPLAY INVISIBLE (-3125 4300);
FORCEPROP 1 LAST PATH I190
J 0
(-3452 4425);
DISPLAY 0.872340 (-3452 4425);
PAINT GREEN (-3452 4425);
DISPLAY INVISIBLE (-3452 4425);
FORCEADD TAP..1
(-3450 4375);
FORCEPROP 3 LASTPIN (-3500 4375) SIG_NAME M_B_CPU1_SA_DQ<30>
J 0
(-3490 4385);
DISPLAY 0.659574 (-3490 4385);
PAINT MONO (-3490 4385);
DISPLAY INVISIBLE (-3490 4385);
FORCEPROP 1 LASTPIN (-3500 4375) BN 30
J 0
(-3512 4383);
DISPLAY 0.489362 (-3512 4383);
PAINT GREEN (-3512 4383);
FORCEPROP 2 LAST CDS_LIB mstr_standard
J 0
(-3450 4375);
DISPLAY 0.723404 (-3450 4375);
PAINT MONO (-3450 4375);
DISPLAY INVISIBLE (-3450 4375);
FORCEPROP 1 LAST BODY_TYPE PLUMBING
J 0
(-3450 4425);
DISPLAY 0.872340 (-3450 4425);
PAINT GREEN (-3450 4425);
DISPLAY INVISIBLE (-3450 4425);
FORCEPROP 1 LAST HDL_TAP TRUE
J 0
(-3125 4250);
DISPLAY 0.872340 (-3125 4250);
DISPLAY INVISIBLE (-3125 4250);
FORCEPROP 1 LAST PATH I191
J 0
(-3452 4375);
DISPLAY 0.872340 (-3452 4375);
PAINT GREEN (-3452 4375);
DISPLAY INVISIBLE (-3452 4375);
FORCEADD TAP..1
(-3450 4475);
FORCEPROP 3 LASTPIN (-3500 4475) SIG_NAME M_B_CPU1_SA_DQ<28>
J 0
(-3490 4485);
DISPLAY 0.659574 (-3490 4485);
PAINT MONO (-3490 4485);
DISPLAY INVISIBLE (-3490 4485);
FORCEPROP 1 LASTPIN (-3500 4475) BN 28
J 0
(-3512 4483);
DISPLAY 0.489362 (-3512 4483);
PAINT GREEN (-3512 4483);
FORCEPROP 2 LAST CDS_LIB mstr_standard
J 0
(-3450 4475);
DISPLAY 0.723404 (-3450 4475);
PAINT MONO (-3450 4475);
DISPLAY INVISIBLE (-3450 4475);
FORCEPROP 1 LAST BODY_TYPE PLUMBING
J 0
(-3450 4525);
DISPLAY 0.872340 (-3450 4525);
PAINT GREEN (-3450 4525);
DISPLAY INVISIBLE (-3450 4525);
FORCEPROP 1 LAST HDL_TAP TRUE
J 0
(-3125 4350);
DISPLAY 0.872340 (-3125 4350);
DISPLAY INVISIBLE (-3125 4350);
FORCEPROP 1 LAST PATH I192
J 0
(-3452 4475);
DISPLAY 0.872340 (-3452 4475);
PAINT GREEN (-3452 4475);
DISPLAY INVISIBLE (-3452 4475);
FORCEADD TAP..1
(-3450 4325);
FORCEPROP 3 LASTPIN (-3500 4325) SIG_NAME M_B_CPU1_SA_DQ<31>
J 0
(-3490 4335);
DISPLAY 0.659574 (-3490 4335);
PAINT MONO (-3490 4335);
DISPLAY INVISIBLE (-3490 4335);
FORCEPROP 1 LASTPIN (-3500 4325) BN 31
J 0
(-3512 4333);
DISPLAY 0.489362 (-3512 4333);
PAINT GREEN (-3512 4333);
FORCEPROP 2 LAST CDS_LIB mstr_standard
J 0
(-3450 4325);
DISPLAY 0.723404 (-3450 4325);
PAINT MONO (-3450 4325);
DISPLAY INVISIBLE (-3450 4325);
FORCEPROP 1 LAST BODY_TYPE PLUMBING
J 0
(-3450 4375);
DISPLAY 0.872340 (-3450 4375);
PAINT GREEN (-3450 4375);
DISPLAY INVISIBLE (-3450 4375);
FORCEPROP 1 LAST HDL_TAP TRUE
J 0
(-3125 4200);
DISPLAY 0.872340 (-3125 4200);
DISPLAY INVISIBLE (-3125 4200);
FORCEPROP 1 LAST PATH I193
J 0
(-3452 4325);
DISPLAY 0.872340 (-3452 4325);
PAINT GREEN (-3452 4325);
DISPLAY INVISIBLE (-3452 4325);
FORCEADD TAP..1
(-3450 4125);
FORCEPROP 3 LASTPIN (-3500 4125) SIG_NAME M_B_CPU1_SB_DQ<2>
J 0
(-3490 4135);
DISPLAY 0.659574 (-3490 4135);
PAINT MONO (-3490 4135);
DISPLAY INVISIBLE (-3490 4135);
FORCEPROP 1 LASTPIN (-3500 4125) BN 2
J 0
(-3512 4133);
DISPLAY 0.489362 (-3512 4133);
PAINT GREEN (-3512 4133);
FORCEPROP 2 LAST CDS_LIB mstr_standard
J 0
(-3450 4125);
DISPLAY 0.723404 (-3450 4125);
PAINT MONO (-3450 4125);
DISPLAY INVISIBLE (-3450 4125);
FORCEPROP 1 LAST BODY_TYPE PLUMBING
J 0
(-3450 4175);
DISPLAY 0.872340 (-3450 4175);
PAINT GREEN (-3450 4175);
DISPLAY INVISIBLE (-3450 4175);
FORCEPROP 1 LAST HDL_TAP TRUE
J 0
(-3125 4000);
DISPLAY 0.872340 (-3125 4000);
DISPLAY INVISIBLE (-3125 4000);
FORCEPROP 1 LAST PATH I194
J 0
(-3452 4125);
DISPLAY 0.872340 (-3452 4125);
PAINT GREEN (-3452 4125);
DISPLAY INVISIBLE (-3452 4125);
FORCEADD TAP..1
(-3450 4175);
FORCEPROP 3 LASTPIN (-3500 4175) SIG_NAME M_B_CPU1_SB_DQ<1>
J 0
(-3490 4185);
DISPLAY 0.659574 (-3490 4185);
PAINT MONO (-3490 4185);
DISPLAY INVISIBLE (-3490 4185);
FORCEPROP 1 LASTPIN (-3500 4175) BN 1
J 0
(-3512 4183);
DISPLAY 0.489362 (-3512 4183);
PAINT GREEN (-3512 4183);
FORCEPROP 2 LAST CDS_LIB mstr_standard
J 0
(-3450 4175);
DISPLAY 0.723404 (-3450 4175);
PAINT MONO (-3450 4175);
DISPLAY INVISIBLE (-3450 4175);
FORCEPROP 1 LAST BODY_TYPE PLUMBING
J 0
(-3450 4225);
DISPLAY 0.872340 (-3450 4225);
PAINT GREEN (-3450 4225);
DISPLAY INVISIBLE (-3450 4225);
FORCEPROP 1 LAST HDL_TAP TRUE
J 0
(-3125 4050);
DISPLAY 0.872340 (-3125 4050);
DISPLAY INVISIBLE (-3125 4050);
FORCEPROP 1 LAST PATH I195
J 0
(-3452 4175);
DISPLAY 0.872340 (-3452 4175);
PAINT GREEN (-3452 4175);
DISPLAY INVISIBLE (-3452 4175);
FORCEADD TAP..1
(-3450 4225);
FORCEPROP 3 LASTPIN (-3500 4225) SIG_NAME M_B_CPU1_SB_DQ<0>
J 0
(-3490 4235);
DISPLAY 0.659574 (-3490 4235);
PAINT MONO (-3490 4235);
DISPLAY INVISIBLE (-3490 4235);
FORCEPROP 1 LASTPIN (-3500 4225) BN 0
J 0
(-3512 4233);
DISPLAY 0.489362 (-3512 4233);
PAINT GREEN (-3512 4233);
FORCEPROP 2 LAST CDS_LIB mstr_standard
J 0
(-3450 4225);
DISPLAY 0.723404 (-3450 4225);
PAINT MONO (-3450 4225);
DISPLAY INVISIBLE (-3450 4225);
FORCEPROP 1 LAST BODY_TYPE PLUMBING
J 0
(-3450 4275);
DISPLAY 0.872340 (-3450 4275);
PAINT GREEN (-3450 4275);
DISPLAY INVISIBLE (-3450 4275);
FORCEPROP 1 LAST HDL_TAP TRUE
J 0
(-3125 4100);
DISPLAY 0.872340 (-3125 4100);
DISPLAY INVISIBLE (-3125 4100);
FORCEPROP 1 LAST PATH I196
J 0
(-3452 4225);
DISPLAY 0.872340 (-3452 4225);
PAINT GREEN (-3452 4225);
DISPLAY INVISIBLE (-3452 4225);
FORCEADD OFFPAGE..6
R 2
(-2850 2475);
FORCEPROP 2 LAST $XR0 99 
J 0
(-2636 2475);
DISPLAY 0.638298 (-2636 2475);
PAINT MONO (-2636 2475);
FORCEPROP 2 LAST CDS_LIB mstr_standard
J 2
(-2850 2475);
DISPLAY 0.723404 (-2850 2475);
PAINT MONO (-2850 2475);
DISPLAY INVISIBLE (-2850 2475);
FORCEPROP 1 LAST OFFPAGE TRUE
J 2
(-3175 2350);
DISPLAY 0.872340 (-3175 2350);
PAINT GREEN (-3175 2350);
DISPLAY INVISIBLE (-3175 2350);
FORCEPROP 1 LAST COMMENT_BODY TRUE
J 2
(-2950 2400);
DISPLAY 0.872340 (-2950 2400);
PAINT GREEN (-2950 2400);
DISPLAY INVISIBLE (-2950 2400);
FORCEPROP 2 LAST PATH I197
J 0
(-2625 2525);
DISPLAY 1.021277 (-2625 2525);
DISPLAY INVISIBLE (-2625 2525);
FORCEADD TAP..1
(-3450 4075);
FORCEPROP 3 LASTPIN (-3500 4075) SIG_NAME M_B_CPU1_SB_DQ<3>
J 0
(-3490 4085);
DISPLAY 0.659574 (-3490 4085);
PAINT MONO (-3490 4085);
DISPLAY INVISIBLE (-3490 4085);
FORCEPROP 1 LASTPIN (-3500 4075) BN 3
J 0
(-3512 4083);
DISPLAY 0.489362 (-3512 4083);
PAINT GREEN (-3512 4083);
FORCEPROP 2 LAST CDS_LIB mstr_standard
J 0
(-3450 4075);
DISPLAY 0.723404 (-3450 4075);
PAINT MONO (-3450 4075);
DISPLAY INVISIBLE (-3450 4075);
FORCEPROP 1 LAST BODY_TYPE PLUMBING
J 0
(-3450 4125);
DISPLAY 0.872340 (-3450 4125);
PAINT GREEN (-3450 4125);
DISPLAY INVISIBLE (-3450 4125);
FORCEPROP 1 LAST HDL_TAP TRUE
J 0
(-3125 3950);
DISPLAY 0.872340 (-3125 3950);
DISPLAY INVISIBLE (-3125 3950);
FORCEPROP 1 LAST PATH I198
J 0
(-3452 4075);
DISPLAY 0.872340 (-3452 4075);
PAINT GREEN (-3452 4075);
DISPLAY INVISIBLE (-3452 4075);
FORCEADD TAP..1
(-3450 4025);
FORCEPROP 3 LASTPIN (-3500 4025) SIG_NAME M_B_CPU1_SB_DQ<4>
J 0
(-3490 4035);
DISPLAY 0.659574 (-3490 4035);
PAINT MONO (-3490 4035);
DISPLAY INVISIBLE (-3490 4035);
FORCEPROP 1 LASTPIN (-3500 4025) BN 4
J 0
(-3512 4033);
DISPLAY 0.489362 (-3512 4033);
PAINT GREEN (-3512 4033);
FORCEPROP 2 LAST CDS_LIB mstr_standard
J 0
(-3450 4025);
DISPLAY 0.723404 (-3450 4025);
PAINT MONO (-3450 4025);
DISPLAY INVISIBLE (-3450 4025);
FORCEPROP 1 LAST BODY_TYPE PLUMBING
J 0
(-3450 4075);
DISPLAY 0.872340 (-3450 4075);
PAINT GREEN (-3450 4075);
DISPLAY INVISIBLE (-3450 4075);
FORCEPROP 1 LAST HDL_TAP TRUE
J 0
(-3125 3900);
DISPLAY 0.872340 (-3125 3900);
DISPLAY INVISIBLE (-3125 3900);
FORCEPROP 1 LAST PATH I199
J 0
(-3452 4025);
DISPLAY 0.872340 (-3452 4025);
PAINT GREEN (-3452 4025);
DISPLAY INVISIBLE (-3452 4025);
FORCEADD TAP..1
(-3450 3975);
FORCEPROP 3 LASTPIN (-3500 3975) SIG_NAME M_B_CPU1_SB_DQ<5>
J 0
(-3490 3985);
DISPLAY 0.659574 (-3490 3985);
PAINT MONO (-3490 3985);
DISPLAY INVISIBLE (-3490 3985);
FORCEPROP 1 LASTPIN (-3500 3975) BN 5
J 0
(-3512 3983);
DISPLAY 0.489362 (-3512 3983);
PAINT GREEN (-3512 3983);
FORCEPROP 2 LAST CDS_LIB mstr_standard
J 0
(-3450 3975);
DISPLAY 0.723404 (-3450 3975);
PAINT MONO (-3450 3975);
DISPLAY INVISIBLE (-3450 3975);
FORCEPROP 1 LAST BODY_TYPE PLUMBING
J 0
(-3450 4025);
DISPLAY 0.872340 (-3450 4025);
PAINT GREEN (-3450 4025);
DISPLAY INVISIBLE (-3450 4025);
FORCEPROP 1 LAST HDL_TAP TRUE
J 0
(-3125 3850);
DISPLAY 0.872340 (-3125 3850);
DISPLAY INVISIBLE (-3125 3850);
FORCEPROP 1 LAST PATH I200
J 0
(-3452 3975);
DISPLAY 0.872340 (-3452 3975);
PAINT GREEN (-3452 3975);
DISPLAY INVISIBLE (-3452 3975);
FORCEADD TAP..1
(-3450 3875);
FORCEPROP 3 LASTPIN (-3500 3875) SIG_NAME M_B_CPU1_SB_DQ<7>
J 0
(-3490 3885);
DISPLAY 0.659574 (-3490 3885);
PAINT MONO (-3490 3885);
DISPLAY INVISIBLE (-3490 3885);
FORCEPROP 1 LASTPIN (-3500 3875) BN 7
J 0
(-3512 3883);
DISPLAY 0.489362 (-3512 3883);
PAINT GREEN (-3512 3883);
FORCEPROP 2 LAST CDS_LIB mstr_standard
J 0
(-3450 3875);
DISPLAY 0.723404 (-3450 3875);
PAINT MONO (-3450 3875);
DISPLAY INVISIBLE (-3450 3875);
FORCEPROP 1 LAST BODY_TYPE PLUMBING
J 0
(-3450 3925);
DISPLAY 0.872340 (-3450 3925);
PAINT GREEN (-3450 3925);
DISPLAY INVISIBLE (-3450 3925);
FORCEPROP 1 LAST HDL_TAP TRUE
J 0
(-3125 3750);
DISPLAY 0.872340 (-3125 3750);
DISPLAY INVISIBLE (-3125 3750);
FORCEPROP 1 LAST PATH I201
J 0
(-3452 3875);
DISPLAY 0.872340 (-3452 3875);
PAINT GREEN (-3452 3875);
DISPLAY INVISIBLE (-3452 3875);
FORCEADD TAP..1
(-3450 3925);
FORCEPROP 3 LASTPIN (-3500 3925) SIG_NAME M_B_CPU1_SB_DQ<6>
J 0
(-3490 3935);
DISPLAY 0.659574 (-3490 3935);
PAINT MONO (-3490 3935);
DISPLAY INVISIBLE (-3490 3935);
FORCEPROP 1 LASTPIN (-3500 3925) BN 6
J 0
(-3512 3933);
DISPLAY 0.489362 (-3512 3933);
PAINT GREEN (-3512 3933);
FORCEPROP 2 LAST CDS_LIB mstr_standard
J 0
(-3450 3925);
DISPLAY 0.723404 (-3450 3925);
PAINT MONO (-3450 3925);
DISPLAY INVISIBLE (-3450 3925);
FORCEPROP 1 LAST BODY_TYPE PLUMBING
J 0
(-3450 3975);
DISPLAY 0.872340 (-3450 3975);
PAINT GREEN (-3450 3975);
DISPLAY INVISIBLE (-3450 3975);
FORCEPROP 1 LAST HDL_TAP TRUE
J 0
(-3125 3800);
DISPLAY 0.872340 (-3125 3800);
DISPLAY INVISIBLE (-3125 3800);
FORCEPROP 1 LAST PATH I202
J 0
(-3452 3925);
DISPLAY 0.872340 (-3452 3925);
PAINT GREEN (-3452 3925);
DISPLAY INVISIBLE (-3452 3925);
FORCEADD TAP..1
(-3450 3775);
FORCEPROP 3 LASTPIN (-3500 3775) SIG_NAME M_B_CPU1_SB_DQ<8>
J 0
(-3490 3785);
DISPLAY 0.659574 (-3490 3785);
PAINT MONO (-3490 3785);
DISPLAY INVISIBLE (-3490 3785);
FORCEPROP 1 LASTPIN (-3500 3775) BN 8
J 0
(-3512 3783);
DISPLAY 0.489362 (-3512 3783);
PAINT GREEN (-3512 3783);
FORCEPROP 2 LAST CDS_LIB mstr_standard
J 0
(-3450 3775);
DISPLAY 0.723404 (-3450 3775);
PAINT MONO (-3450 3775);
DISPLAY INVISIBLE (-3450 3775);
FORCEPROP 1 LAST BODY_TYPE PLUMBING
J 0
(-3450 3825);
DISPLAY 0.872340 (-3450 3825);
PAINT GREEN (-3450 3825);
DISPLAY INVISIBLE (-3450 3825);
FORCEPROP 1 LAST HDL_TAP TRUE
J 0
(-3125 3650);
DISPLAY 0.872340 (-3125 3650);
DISPLAY INVISIBLE (-3125 3650);
FORCEPROP 1 LAST PATH I203
J 0
(-3452 3775);
DISPLAY 0.872340 (-3452 3775);
PAINT GREEN (-3452 3775);
DISPLAY INVISIBLE (-3452 3775);
FORCEADD TAP..1
(-3450 3625);
FORCEPROP 3 LASTPIN (-3500 3625) SIG_NAME M_B_CPU1_SB_DQ<11>
J 0
(-3490 3635);
DISPLAY 0.659574 (-3490 3635);
PAINT MONO (-3490 3635);
DISPLAY INVISIBLE (-3490 3635);
FORCEPROP 1 LASTPIN (-3500 3625) BN 11
J 0
(-3512 3633);
DISPLAY 0.489362 (-3512 3633);
PAINT GREEN (-3512 3633);
FORCEPROP 2 LAST CDS_LIB mstr_standard
J 0
(-3450 3625);
DISPLAY 0.723404 (-3450 3625);
PAINT MONO (-3450 3625);
DISPLAY INVISIBLE (-3450 3625);
FORCEPROP 1 LAST BODY_TYPE PLUMBING
J 0
(-3450 3675);
DISPLAY 0.872340 (-3450 3675);
PAINT GREEN (-3450 3675);
DISPLAY INVISIBLE (-3450 3675);
FORCEPROP 1 LAST HDL_TAP TRUE
J 0
(-3125 3500);
DISPLAY 0.872340 (-3125 3500);
DISPLAY INVISIBLE (-3125 3500);
FORCEPROP 1 LAST PATH I204
J 0
(-3452 3625);
DISPLAY 0.872340 (-3452 3625);
PAINT GREEN (-3452 3625);
DISPLAY INVISIBLE (-3452 3625);
FORCEADD TAP..1
(-3450 3725);
FORCEPROP 3 LASTPIN (-3500 3725) SIG_NAME M_B_CPU1_SB_DQ<9>
J 0
(-3490 3735);
DISPLAY 0.659574 (-3490 3735);
PAINT MONO (-3490 3735);
DISPLAY INVISIBLE (-3490 3735);
FORCEPROP 1 LASTPIN (-3500 3725) BN 9
J 0
(-3512 3733);
DISPLAY 0.489362 (-3512 3733);
PAINT GREEN (-3512 3733);
FORCEPROP 2 LAST CDS_LIB mstr_standard
J 0
(-3450 3725);
DISPLAY 0.723404 (-3450 3725);
PAINT MONO (-3450 3725);
DISPLAY INVISIBLE (-3450 3725);
FORCEPROP 1 LAST BODY_TYPE PLUMBING
J 0
(-3450 3775);
DISPLAY 0.872340 (-3450 3775);
PAINT GREEN (-3450 3775);
DISPLAY INVISIBLE (-3450 3775);
FORCEPROP 1 LAST HDL_TAP TRUE
J 0
(-3125 3600);
DISPLAY 0.872340 (-3125 3600);
DISPLAY INVISIBLE (-3125 3600);
FORCEPROP 1 LAST PATH I205
J 0
(-3452 3725);
DISPLAY 0.872340 (-3452 3725);
PAINT GREEN (-3452 3725);
DISPLAY INVISIBLE (-3452 3725);
FORCEADD TAP..1
(-3450 3675);
FORCEPROP 3 LASTPIN (-3500 3675) SIG_NAME M_B_CPU1_SB_DQ<10>
J 0
(-3490 3685);
DISPLAY 0.659574 (-3490 3685);
PAINT MONO (-3490 3685);
DISPLAY INVISIBLE (-3490 3685);
FORCEPROP 1 LASTPIN (-3500 3675) BN 10
J 0
(-3512 3683);
DISPLAY 0.489362 (-3512 3683);
PAINT GREEN (-3512 3683);
FORCEPROP 2 LAST CDS_LIB mstr_standard
J 0
(-3450 3675);
DISPLAY 0.723404 (-3450 3675);
PAINT MONO (-3450 3675);
DISPLAY INVISIBLE (-3450 3675);
FORCEPROP 1 LAST BODY_TYPE PLUMBING
J 0
(-3450 3725);
DISPLAY 0.872340 (-3450 3725);
PAINT GREEN (-3450 3725);
DISPLAY INVISIBLE (-3450 3725);
FORCEPROP 1 LAST HDL_TAP TRUE
J 0
(-3125 3550);
DISPLAY 0.872340 (-3125 3550);
DISPLAY INVISIBLE (-3125 3550);
FORCEPROP 1 LAST PATH I206
J 0
(-3452 3675);
DISPLAY 0.872340 (-3452 3675);
PAINT GREEN (-3452 3675);
DISPLAY INVISIBLE (-3452 3675);
FORCEADD TAP..1
(-3450 3575);
FORCEPROP 3 LASTPIN (-3500 3575) SIG_NAME M_B_CPU1_SB_DQ<12>
J 0
(-3490 3585);
DISPLAY 0.659574 (-3490 3585);
PAINT MONO (-3490 3585);
DISPLAY INVISIBLE (-3490 3585);
FORCEPROP 1 LASTPIN (-3500 3575) BN 12
J 0
(-3512 3583);
DISPLAY 0.489362 (-3512 3583);
PAINT GREEN (-3512 3583);
FORCEPROP 2 LAST CDS_LIB mstr_standard
J 0
(-3450 3575);
DISPLAY 0.723404 (-3450 3575);
PAINT MONO (-3450 3575);
DISPLAY INVISIBLE (-3450 3575);
FORCEPROP 1 LAST BODY_TYPE PLUMBING
J 0
(-3450 3625);
DISPLAY 0.872340 (-3450 3625);
PAINT GREEN (-3450 3625);
DISPLAY INVISIBLE (-3450 3625);
FORCEPROP 1 LAST HDL_TAP TRUE
J 0
(-3125 3450);
DISPLAY 0.872340 (-3125 3450);
DISPLAY INVISIBLE (-3125 3450);
FORCEPROP 1 LAST PATH I207
J 0
(-3452 3575);
DISPLAY 0.872340 (-3452 3575);
PAINT GREEN (-3452 3575);
DISPLAY INVISIBLE (-3452 3575);
FORCEADD TAP..1
(-3450 3525);
FORCEPROP 3 LASTPIN (-3500 3525) SIG_NAME M_B_CPU1_SB_DQ<13>
J 0
(-3490 3535);
DISPLAY 0.659574 (-3490 3535);
PAINT MONO (-3490 3535);
DISPLAY INVISIBLE (-3490 3535);
FORCEPROP 1 LASTPIN (-3500 3525) BN 13
J 0
(-3512 3533);
DISPLAY 0.489362 (-3512 3533);
PAINT GREEN (-3512 3533);
FORCEPROP 2 LAST CDS_LIB mstr_standard
J 0
(-3450 3525);
DISPLAY 0.723404 (-3450 3525);
PAINT MONO (-3450 3525);
DISPLAY INVISIBLE (-3450 3525);
FORCEPROP 1 LAST BODY_TYPE PLUMBING
J 0
(-3450 3575);
DISPLAY 0.872340 (-3450 3575);
PAINT GREEN (-3450 3575);
DISPLAY INVISIBLE (-3450 3575);
FORCEPROP 1 LAST HDL_TAP TRUE
J 0
(-3125 3400);
DISPLAY 0.872340 (-3125 3400);
DISPLAY INVISIBLE (-3125 3400);
FORCEPROP 1 LAST PATH I208
J 0
(-3452 3525);
DISPLAY 0.872340 (-3452 3525);
PAINT GREEN (-3452 3525);
DISPLAY INVISIBLE (-3452 3525);
FORCEADD TAP..1
(-3450 3425);
FORCEPROP 3 LASTPIN (-3500 3425) SIG_NAME M_B_CPU1_SB_DQ<15>
J 0
(-3490 3435);
DISPLAY 0.659574 (-3490 3435);
PAINT MONO (-3490 3435);
DISPLAY INVISIBLE (-3490 3435);
FORCEPROP 1 LASTPIN (-3500 3425) BN 15
J 0
(-3512 3433);
DISPLAY 0.489362 (-3512 3433);
PAINT GREEN (-3512 3433);
FORCEPROP 2 LAST CDS_LIB mstr_standard
J 0
(-3450 3425);
DISPLAY 0.723404 (-3450 3425);
PAINT MONO (-3450 3425);
DISPLAY INVISIBLE (-3450 3425);
FORCEPROP 1 LAST BODY_TYPE PLUMBING
J 0
(-3450 3475);
DISPLAY 0.872340 (-3450 3475);
PAINT GREEN (-3450 3475);
DISPLAY INVISIBLE (-3450 3475);
FORCEPROP 1 LAST HDL_TAP TRUE
J 0
(-3125 3300);
DISPLAY 0.872340 (-3125 3300);
DISPLAY INVISIBLE (-3125 3300);
FORCEPROP 1 LAST PATH I209
J 0
(-3452 3425);
DISPLAY 0.872340 (-3452 3425);
PAINT GREEN (-3452 3425);
DISPLAY INVISIBLE (-3452 3425);
FORCEADD TAP..1
(-3450 3475);
FORCEPROP 3 LASTPIN (-3500 3475) SIG_NAME M_B_CPU1_SB_DQ<14>
J 0
(-3490 3485);
DISPLAY 0.659574 (-3490 3485);
PAINT MONO (-3490 3485);
DISPLAY INVISIBLE (-3490 3485);
FORCEPROP 1 LASTPIN (-3500 3475) BN 14
J 0
(-3512 3483);
DISPLAY 0.489362 (-3512 3483);
PAINT GREEN (-3512 3483);
FORCEPROP 2 LAST CDS_LIB mstr_standard
J 0
(-3450 3475);
DISPLAY 0.723404 (-3450 3475);
PAINT MONO (-3450 3475);
DISPLAY INVISIBLE (-3450 3475);
FORCEPROP 1 LAST BODY_TYPE PLUMBING
J 0
(-3450 3525);
DISPLAY 0.872340 (-3450 3525);
PAINT GREEN (-3450 3525);
DISPLAY INVISIBLE (-3450 3525);
FORCEPROP 1 LAST HDL_TAP TRUE
J 0
(-3125 3350);
DISPLAY 0.872340 (-3125 3350);
DISPLAY INVISIBLE (-3125 3350);
FORCEPROP 1 LAST PATH I210
J 0
(-3452 3475);
DISPLAY 0.872340 (-3452 3475);
PAINT GREEN (-3452 3475);
DISPLAY INVISIBLE (-3452 3475);
FORCEADD TAP..1
(-3450 3325);
FORCEPROP 3 LASTPIN (-3500 3325) SIG_NAME M_B_CPU1_SB_DQ<16>
J 0
(-3490 3335);
DISPLAY 0.659574 (-3490 3335);
PAINT MONO (-3490 3335);
DISPLAY INVISIBLE (-3490 3335);
FORCEPROP 1 LASTPIN (-3500 3325) BN 16
J 0
(-3512 3333);
DISPLAY 0.489362 (-3512 3333);
PAINT GREEN (-3512 3333);
FORCEPROP 2 LAST CDS_LIB mstr_standard
J 0
(-3450 3325);
DISPLAY 0.723404 (-3450 3325);
PAINT MONO (-3450 3325);
DISPLAY INVISIBLE (-3450 3325);
FORCEPROP 1 LAST BODY_TYPE PLUMBING
J 0
(-3450 3375);
DISPLAY 0.872340 (-3450 3375);
PAINT GREEN (-3450 3375);
DISPLAY INVISIBLE (-3450 3375);
FORCEPROP 1 LAST HDL_TAP TRUE
J 0
(-3125 3200);
DISPLAY 0.872340 (-3125 3200);
DISPLAY INVISIBLE (-3125 3200);
FORCEPROP 1 LAST PATH I211
J 0
(-3452 3325);
DISPLAY 0.872340 (-3452 3325);
PAINT GREEN (-3452 3325);
DISPLAY INVISIBLE (-3452 3325);
FORCEADD TAP..1
(-3450 3275);
FORCEPROP 3 LASTPIN (-3500 3275) SIG_NAME M_B_CPU1_SB_DQ<17>
J 0
(-3490 3285);
DISPLAY 0.659574 (-3490 3285);
PAINT MONO (-3490 3285);
DISPLAY INVISIBLE (-3490 3285);
FORCEPROP 1 LASTPIN (-3500 3275) BN 17
J 0
(-3512 3283);
DISPLAY 0.489362 (-3512 3283);
PAINT GREEN (-3512 3283);
FORCEPROP 2 LAST CDS_LIB mstr_standard
J 0
(-3450 3275);
DISPLAY 0.723404 (-3450 3275);
PAINT MONO (-3450 3275);
DISPLAY INVISIBLE (-3450 3275);
FORCEPROP 1 LAST BODY_TYPE PLUMBING
J 0
(-3450 3325);
DISPLAY 0.872340 (-3450 3325);
PAINT GREEN (-3450 3325);
DISPLAY INVISIBLE (-3450 3325);
FORCEPROP 1 LAST HDL_TAP TRUE
J 0
(-3125 3150);
DISPLAY 0.872340 (-3125 3150);
DISPLAY INVISIBLE (-3125 3150);
FORCEPROP 1 LAST PATH I212
J 0
(-3452 3275);
DISPLAY 0.872340 (-3452 3275);
PAINT GREEN (-3452 3275);
DISPLAY INVISIBLE (-3452 3275);
FORCEADD TAP..1
(-3450 3225);
FORCEPROP 3 LASTPIN (-3500 3225) SIG_NAME M_B_CPU1_SB_DQ<18>
J 0
(-3490 3235);
DISPLAY 0.659574 (-3490 3235);
PAINT MONO (-3490 3235);
DISPLAY INVISIBLE (-3490 3235);
FORCEPROP 1 LASTPIN (-3500 3225) BN 18
J 0
(-3512 3233);
DISPLAY 0.489362 (-3512 3233);
PAINT GREEN (-3512 3233);
FORCEPROP 2 LAST CDS_LIB mstr_standard
J 0
(-3450 3225);
DISPLAY 0.723404 (-3450 3225);
PAINT MONO (-3450 3225);
DISPLAY INVISIBLE (-3450 3225);
FORCEPROP 1 LAST BODY_TYPE PLUMBING
J 0
(-3450 3275);
DISPLAY 0.872340 (-3450 3275);
PAINT GREEN (-3450 3275);
DISPLAY INVISIBLE (-3450 3275);
FORCEPROP 1 LAST HDL_TAP TRUE
J 0
(-3125 3100);
DISPLAY 0.872340 (-3125 3100);
DISPLAY INVISIBLE (-3125 3100);
FORCEPROP 1 LAST PATH I213
J 0
(-3452 3225);
DISPLAY 0.872340 (-3452 3225);
PAINT GREEN (-3452 3225);
DISPLAY INVISIBLE (-3452 3225);
FORCEADD TAP..1
(-3450 3075);
FORCEPROP 3 LASTPIN (-3500 3075) SIG_NAME M_B_CPU1_SB_DQ<21>
J 0
(-3490 3085);
DISPLAY 0.659574 (-3490 3085);
PAINT MONO (-3490 3085);
DISPLAY INVISIBLE (-3490 3085);
FORCEPROP 1 LASTPIN (-3500 3075) BN 21
J 0
(-3512 3083);
DISPLAY 0.489362 (-3512 3083);
PAINT GREEN (-3512 3083);
FORCEPROP 2 LAST CDS_LIB mstr_standard
J 0
(-3450 3075);
DISPLAY 0.723404 (-3450 3075);
PAINT MONO (-3450 3075);
DISPLAY INVISIBLE (-3450 3075);
FORCEPROP 1 LAST BODY_TYPE PLUMBING
J 0
(-3450 3125);
DISPLAY 0.872340 (-3450 3125);
PAINT GREEN (-3450 3125);
DISPLAY INVISIBLE (-3450 3125);
FORCEPROP 1 LAST HDL_TAP TRUE
J 0
(-3125 2950);
DISPLAY 0.872340 (-3125 2950);
DISPLAY INVISIBLE (-3125 2950);
FORCEPROP 1 LAST PATH I214
J 0
(-3452 3075);
DISPLAY 0.872340 (-3452 3075);
PAINT GREEN (-3452 3075);
DISPLAY INVISIBLE (-3452 3075);
FORCEADD TAP..1
(-3450 3125);
FORCEPROP 3 LASTPIN (-3500 3125) SIG_NAME M_B_CPU1_SB_DQ<20>
J 0
(-3490 3135);
DISPLAY 0.659574 (-3490 3135);
PAINT MONO (-3490 3135);
DISPLAY INVISIBLE (-3490 3135);
FORCEPROP 1 LASTPIN (-3500 3125) BN 20
J 0
(-3512 3133);
DISPLAY 0.489362 (-3512 3133);
PAINT GREEN (-3512 3133);
FORCEPROP 2 LAST CDS_LIB mstr_standard
J 0
(-3450 3125);
DISPLAY 0.723404 (-3450 3125);
PAINT MONO (-3450 3125);
DISPLAY INVISIBLE (-3450 3125);
FORCEPROP 1 LAST BODY_TYPE PLUMBING
J 0
(-3450 3175);
DISPLAY 0.872340 (-3450 3175);
PAINT GREEN (-3450 3175);
DISPLAY INVISIBLE (-3450 3175);
FORCEPROP 1 LAST HDL_TAP TRUE
J 0
(-3125 3000);
DISPLAY 0.872340 (-3125 3000);
DISPLAY INVISIBLE (-3125 3000);
FORCEPROP 1 LAST PATH I215
J 0
(-3452 3125);
DISPLAY 0.872340 (-3452 3125);
PAINT GREEN (-3452 3125);
DISPLAY INVISIBLE (-3452 3125);
FORCEADD TAP..1
(-3450 3175);
FORCEPROP 3 LASTPIN (-3500 3175) SIG_NAME M_B_CPU1_SB_DQ<19>
J 0
(-3490 3185);
DISPLAY 0.659574 (-3490 3185);
PAINT MONO (-3490 3185);
DISPLAY INVISIBLE (-3490 3185);
FORCEPROP 1 LASTPIN (-3500 3175) BN 19
J 0
(-3512 3183);
DISPLAY 0.489362 (-3512 3183);
PAINT GREEN (-3512 3183);
FORCEPROP 2 LAST CDS_LIB mstr_standard
J 0
(-3450 3175);
DISPLAY 0.723404 (-3450 3175);
PAINT MONO (-3450 3175);
DISPLAY INVISIBLE (-3450 3175);
FORCEPROP 1 LAST BODY_TYPE PLUMBING
J 0
(-3450 3225);
DISPLAY 0.872340 (-3450 3225);
PAINT GREEN (-3450 3225);
DISPLAY INVISIBLE (-3450 3225);
FORCEPROP 1 LAST HDL_TAP TRUE
J 0
(-3125 3050);
DISPLAY 0.872340 (-3125 3050);
DISPLAY INVISIBLE (-3125 3050);
FORCEPROP 1 LAST PATH I216
J 0
(-3452 3175);
DISPLAY 0.872340 (-3452 3175);
PAINT GREEN (-3452 3175);
DISPLAY INVISIBLE (-3452 3175);
FORCEADD TAP..1
(-3450 2825);
FORCEPROP 3 LASTPIN (-3500 2825) SIG_NAME M_B_CPU1_SB_DQ<25>
J 0
(-3490 2835);
DISPLAY 0.659574 (-3490 2835);
PAINT MONO (-3490 2835);
DISPLAY INVISIBLE (-3490 2835);
FORCEPROP 1 LASTPIN (-3500 2825) BN 25
J 0
(-3512 2833);
DISPLAY 0.489362 (-3512 2833);
PAINT GREEN (-3512 2833);
FORCEPROP 2 LAST CDS_LIB mstr_standard
J 0
(-3450 2825);
DISPLAY 0.723404 (-3450 2825);
PAINT MONO (-3450 2825);
DISPLAY INVISIBLE (-3450 2825);
FORCEPROP 1 LAST BODY_TYPE PLUMBING
J 0
(-3450 2875);
DISPLAY 0.872340 (-3450 2875);
PAINT GREEN (-3450 2875);
DISPLAY INVISIBLE (-3450 2875);
FORCEPROP 1 LAST HDL_TAP TRUE
J 0
(-3125 2700);
DISPLAY 0.872340 (-3125 2700);
DISPLAY INVISIBLE (-3125 2700);
FORCEPROP 1 LAST PATH I217
J 0
(-3452 2825);
DISPLAY 0.872340 (-3452 2825);
PAINT GREEN (-3452 2825);
DISPLAY INVISIBLE (-3452 2825);
FORCEADD TAP..1
(-3450 2875);
FORCEPROP 3 LASTPIN (-3500 2875) SIG_NAME M_B_CPU1_SB_DQ<24>
J 0
(-3490 2885);
DISPLAY 0.659574 (-3490 2885);
PAINT MONO (-3490 2885);
DISPLAY INVISIBLE (-3490 2885);
FORCEPROP 1 LASTPIN (-3500 2875) BN 24
J 0
(-3512 2883);
DISPLAY 0.489362 (-3512 2883);
PAINT GREEN (-3512 2883);
FORCEPROP 2 LAST CDS_LIB mstr_standard
J 0
(-3450 2875);
DISPLAY 0.723404 (-3450 2875);
PAINT MONO (-3450 2875);
DISPLAY INVISIBLE (-3450 2875);
FORCEPROP 1 LAST BODY_TYPE PLUMBING
J 0
(-3450 2925);
DISPLAY 0.872340 (-3450 2925);
PAINT GREEN (-3450 2925);
DISPLAY INVISIBLE (-3450 2925);
FORCEPROP 1 LAST HDL_TAP TRUE
J 0
(-3125 2750);
DISPLAY 0.872340 (-3125 2750);
DISPLAY INVISIBLE (-3125 2750);
FORCEPROP 1 LAST PATH I218
J 0
(-3452 2875);
DISPLAY 0.872340 (-3452 2875);
PAINT GREEN (-3452 2875);
DISPLAY INVISIBLE (-3452 2875);
FORCEADD TAP..1
(-3450 3025);
FORCEPROP 3 LASTPIN (-3500 3025) SIG_NAME M_B_CPU1_SB_DQ<22>
J 0
(-3490 3035);
DISPLAY 0.659574 (-3490 3035);
PAINT MONO (-3490 3035);
DISPLAY INVISIBLE (-3490 3035);
FORCEPROP 1 LASTPIN (-3500 3025) BN 22
J 0
(-3512 3033);
DISPLAY 0.489362 (-3512 3033);
PAINT GREEN (-3512 3033);
FORCEPROP 2 LAST CDS_LIB mstr_standard
J 0
(-3450 3025);
DISPLAY 0.723404 (-3450 3025);
PAINT MONO (-3450 3025);
DISPLAY INVISIBLE (-3450 3025);
FORCEPROP 1 LAST BODY_TYPE PLUMBING
J 0
(-3450 3075);
DISPLAY 0.872340 (-3450 3075);
PAINT GREEN (-3450 3075);
DISPLAY INVISIBLE (-3450 3075);
FORCEPROP 1 LAST HDL_TAP TRUE
J 0
(-3125 2900);
DISPLAY 0.872340 (-3125 2900);
DISPLAY INVISIBLE (-3125 2900);
FORCEPROP 1 LAST PATH I219
J 0
(-3452 3025);
DISPLAY 0.872340 (-3452 3025);
PAINT GREEN (-3452 3025);
DISPLAY INVISIBLE (-3452 3025);
FORCEADD TAP..1
(-3450 2975);
FORCEPROP 3 LASTPIN (-3500 2975) SIG_NAME M_B_CPU1_SB_DQ<23>
J 0
(-3490 2985);
DISPLAY 0.659574 (-3490 2985);
PAINT MONO (-3490 2985);
DISPLAY INVISIBLE (-3490 2985);
FORCEPROP 1 LASTPIN (-3500 2975) BN 23
J 0
(-3512 2983);
DISPLAY 0.489362 (-3512 2983);
PAINT GREEN (-3512 2983);
FORCEPROP 2 LAST CDS_LIB mstr_standard
J 0
(-3450 2975);
DISPLAY 0.723404 (-3450 2975);
PAINT MONO (-3450 2975);
DISPLAY INVISIBLE (-3450 2975);
FORCEPROP 1 LAST BODY_TYPE PLUMBING
J 0
(-3450 3025);
DISPLAY 0.872340 (-3450 3025);
PAINT GREEN (-3450 3025);
DISPLAY INVISIBLE (-3450 3025);
FORCEPROP 1 LAST HDL_TAP TRUE
J 0
(-3125 2850);
DISPLAY 0.872340 (-3125 2850);
DISPLAY INVISIBLE (-3125 2850);
FORCEPROP 1 LAST PATH I220
J 0
(-3452 2975);
DISPLAY 0.872340 (-3452 2975);
PAINT GREEN (-3452 2975);
DISPLAY INVISIBLE (-3452 2975);
FORCEADD TAP..1
(-3450 2575);
FORCEPROP 3 LASTPIN (-3500 2575) SIG_NAME M_B_CPU1_SB_DQ<30>
J 0
(-3490 2585);
DISPLAY 0.659574 (-3490 2585);
PAINT MONO (-3490 2585);
DISPLAY INVISIBLE (-3490 2585);
FORCEPROP 1 LASTPIN (-3500 2575) BN 30
J 0
(-3512 2583);
DISPLAY 0.489362 (-3512 2583);
PAINT GREEN (-3512 2583);
FORCEPROP 2 LAST CDS_LIB mstr_standard
J 0
(-3450 2575);
DISPLAY 0.723404 (-3450 2575);
PAINT MONO (-3450 2575);
DISPLAY INVISIBLE (-3450 2575);
FORCEPROP 1 LAST BODY_TYPE PLUMBING
J 0
(-3450 2625);
DISPLAY 0.872340 (-3450 2625);
PAINT GREEN (-3450 2625);
DISPLAY INVISIBLE (-3450 2625);
FORCEPROP 1 LAST HDL_TAP TRUE
J 0
(-3125 2450);
DISPLAY 0.872340 (-3125 2450);
DISPLAY INVISIBLE (-3125 2450);
FORCEPROP 1 LAST PATH I221
J 0
(-3452 2575);
DISPLAY 0.872340 (-3452 2575);
PAINT GREEN (-3452 2575);
DISPLAY INVISIBLE (-3452 2575);
FORCEADD TAP..1
(-3450 2625);
FORCEPROP 3 LASTPIN (-3500 2625) SIG_NAME M_B_CPU1_SB_DQ<29>
J 0
(-3490 2635);
DISPLAY 0.659574 (-3490 2635);
PAINT MONO (-3490 2635);
DISPLAY INVISIBLE (-3490 2635);
FORCEPROP 1 LASTPIN (-3500 2625) BN 29
J 0
(-3512 2633);
DISPLAY 0.489362 (-3512 2633);
PAINT GREEN (-3512 2633);
FORCEPROP 2 LAST CDS_LIB mstr_standard
J 0
(-3450 2625);
DISPLAY 0.723404 (-3450 2625);
PAINT MONO (-3450 2625);
DISPLAY INVISIBLE (-3450 2625);
FORCEPROP 1 LAST BODY_TYPE PLUMBING
J 0
(-3450 2675);
DISPLAY 0.872340 (-3450 2675);
PAINT GREEN (-3450 2675);
DISPLAY INVISIBLE (-3450 2675);
FORCEPROP 1 LAST HDL_TAP TRUE
J 0
(-3125 2500);
DISPLAY 0.872340 (-3125 2500);
DISPLAY INVISIBLE (-3125 2500);
FORCEPROP 1 LAST PATH I222
J 0
(-3452 2625);
DISPLAY 0.872340 (-3452 2625);
PAINT GREEN (-3452 2625);
DISPLAY INVISIBLE (-3452 2625);
FORCEADD TAP..1
(-3450 2675);
FORCEPROP 3 LASTPIN (-3500 2675) SIG_NAME M_B_CPU1_SB_DQ<28>
J 0
(-3490 2685);
DISPLAY 0.659574 (-3490 2685);
PAINT MONO (-3490 2685);
DISPLAY INVISIBLE (-3490 2685);
FORCEPROP 1 LASTPIN (-3500 2675) BN 28
J 0
(-3512 2683);
DISPLAY 0.489362 (-3512 2683);
PAINT GREEN (-3512 2683);
FORCEPROP 2 LAST CDS_LIB mstr_standard
J 0
(-3450 2675);
DISPLAY 0.723404 (-3450 2675);
PAINT MONO (-3450 2675);
DISPLAY INVISIBLE (-3450 2675);
FORCEPROP 1 LAST BODY_TYPE PLUMBING
J 0
(-3450 2725);
DISPLAY 0.872340 (-3450 2725);
PAINT GREEN (-3450 2725);
DISPLAY INVISIBLE (-3450 2725);
FORCEPROP 1 LAST HDL_TAP TRUE
J 0
(-3125 2550);
DISPLAY 0.872340 (-3125 2550);
DISPLAY INVISIBLE (-3125 2550);
FORCEPROP 1 LAST PATH I223
J 0
(-3452 2675);
DISPLAY 0.872340 (-3452 2675);
PAINT GREEN (-3452 2675);
DISPLAY INVISIBLE (-3452 2675);
FORCEADD TAP..1
(-3450 2725);
FORCEPROP 3 LASTPIN (-3500 2725) SIG_NAME M_B_CPU1_SB_DQ<27>
J 0
(-3490 2735);
DISPLAY 0.659574 (-3490 2735);
PAINT MONO (-3490 2735);
DISPLAY INVISIBLE (-3490 2735);
FORCEPROP 1 LASTPIN (-3500 2725) BN 27
J 0
(-3512 2733);
DISPLAY 0.489362 (-3512 2733);
PAINT GREEN (-3512 2733);
FORCEPROP 2 LAST CDS_LIB mstr_standard
J 0
(-3450 2725);
DISPLAY 0.723404 (-3450 2725);
PAINT MONO (-3450 2725);
DISPLAY INVISIBLE (-3450 2725);
FORCEPROP 1 LAST BODY_TYPE PLUMBING
J 0
(-3450 2775);
DISPLAY 0.872340 (-3450 2775);
PAINT GREEN (-3450 2775);
DISPLAY INVISIBLE (-3450 2775);
FORCEPROP 1 LAST HDL_TAP TRUE
J 0
(-3125 2600);
DISPLAY 0.872340 (-3125 2600);
DISPLAY INVISIBLE (-3125 2600);
FORCEPROP 1 LAST PATH I224
J 0
(-3452 2725);
DISPLAY 0.872340 (-3452 2725);
PAINT GREEN (-3452 2725);
DISPLAY INVISIBLE (-3452 2725);
FORCEADD TAP..1
(-3450 2775);
FORCEPROP 3 LASTPIN (-3500 2775) SIG_NAME M_B_CPU1_SB_DQ<26>
J 0
(-3490 2785);
DISPLAY 0.659574 (-3490 2785);
PAINT MONO (-3490 2785);
DISPLAY INVISIBLE (-3490 2785);
FORCEPROP 1 LASTPIN (-3500 2775) BN 26
J 0
(-3512 2783);
DISPLAY 0.489362 (-3512 2783);
PAINT GREEN (-3512 2783);
FORCEPROP 2 LAST CDS_LIB mstr_standard
J 0
(-3450 2775);
DISPLAY 0.723404 (-3450 2775);
PAINT MONO (-3450 2775);
DISPLAY INVISIBLE (-3450 2775);
FORCEPROP 1 LAST BODY_TYPE PLUMBING
J 0
(-3450 2825);
DISPLAY 0.872340 (-3450 2825);
PAINT GREEN (-3450 2825);
DISPLAY INVISIBLE (-3450 2825);
FORCEPROP 1 LAST HDL_TAP TRUE
J 0
(-3125 2650);
DISPLAY 0.872340 (-3125 2650);
DISPLAY INVISIBLE (-3125 2650);
FORCEPROP 1 LAST PATH I225
J 0
(-3452 2775);
DISPLAY 0.872340 (-3452 2775);
PAINT GREEN (-3452 2775);
DISPLAY INVISIBLE (-3452 2775);
FORCEADD TAP..1
(-3450 2325);
FORCEPROP 3 LASTPIN (-3500 2325) SIG_NAME M_B_CPU1_SA_CB<2>
J 0
(-3490 2335);
DISPLAY 0.659574 (-3490 2335);
PAINT MONO (-3490 2335);
DISPLAY INVISIBLE (-3490 2335);
FORCEPROP 1 LASTPIN (-3500 2325) BN 2
J 0
(-3512 2333);
DISPLAY 0.489362 (-3512 2333);
PAINT GREEN (-3512 2333);
FORCEPROP 2 LAST CDS_LIB mstr_standard
J 2
(-3450 2325);
DISPLAY 0.723404 (-3450 2325);
PAINT MONO (-3450 2325);
DISPLAY INVISIBLE (-3450 2325);
FORCEPROP 1 LAST BODY_TYPE PLUMBING
J 0
(-3450 2375);
DISPLAY 0.872340 (-3450 2375);
PAINT GREEN (-3450 2375);
DISPLAY INVISIBLE (-3450 2375);
FORCEPROP 1 LAST HDL_TAP TRUE
J 0
(-3125 2200);
DISPLAY 0.872340 (-3125 2200);
DISPLAY INVISIBLE (-3125 2200);
FORCEPROP 1 LAST PATH I226
J 0
(-3452 2325);
DISPLAY 0.872340 (-3452 2325);
PAINT GREEN (-3452 2325);
DISPLAY INVISIBLE (-3452 2325);
FORCEADD TAP..1
(-3450 2375);
FORCEPROP 3 LASTPIN (-3500 2375) SIG_NAME M_B_CPU1_SA_CB<1>
J 0
(-3490 2385);
DISPLAY 0.659574 (-3490 2385);
PAINT MONO (-3490 2385);
DISPLAY INVISIBLE (-3490 2385);
FORCEPROP 1 LASTPIN (-3500 2375) BN 1
J 0
(-3512 2383);
DISPLAY 0.489362 (-3512 2383);
PAINT GREEN (-3512 2383);
FORCEPROP 2 LAST CDS_LIB mstr_standard
J 2
(-3450 2375);
DISPLAY 0.723404 (-3450 2375);
PAINT MONO (-3450 2375);
DISPLAY INVISIBLE (-3450 2375);
FORCEPROP 1 LAST BODY_TYPE PLUMBING
J 0
(-3450 2425);
DISPLAY 0.872340 (-3450 2425);
PAINT GREEN (-3450 2425);
DISPLAY INVISIBLE (-3450 2425);
FORCEPROP 1 LAST HDL_TAP TRUE
J 0
(-3125 2250);
DISPLAY 0.872340 (-3125 2250);
DISPLAY INVISIBLE (-3125 2250);
FORCEPROP 1 LAST PATH I227
J 0
(-3452 2375);
DISPLAY 0.872340 (-3452 2375);
PAINT GREEN (-3452 2375);
DISPLAY INVISIBLE (-3452 2375);
FORCEADD TAP..1
(-3450 2425);
FORCEPROP 3 LASTPIN (-3500 2425) SIG_NAME M_B_CPU1_SA_CB<0>
J 0
(-3490 2435);
DISPLAY 0.659574 (-3490 2435);
PAINT MONO (-3490 2435);
DISPLAY INVISIBLE (-3490 2435);
FORCEPROP 1 LASTPIN (-3500 2425) BN 0
J 0
(-3512 2433);
DISPLAY 0.489362 (-3512 2433);
PAINT GREEN (-3512 2433);
FORCEPROP 2 LAST CDS_LIB mstr_standard
J 2
(-3450 2425);
DISPLAY 0.723404 (-3450 2425);
PAINT MONO (-3450 2425);
DISPLAY INVISIBLE (-3450 2425);
FORCEPROP 1 LAST BODY_TYPE PLUMBING
J 0
(-3450 2475);
DISPLAY 0.872340 (-3450 2475);
PAINT GREEN (-3450 2475);
DISPLAY INVISIBLE (-3450 2475);
FORCEPROP 1 LAST HDL_TAP TRUE
J 0
(-3125 2300);
DISPLAY 0.872340 (-3125 2300);
DISPLAY INVISIBLE (-3125 2300);
FORCEPROP 1 LAST PATH I228
J 0
(-3452 2425);
DISPLAY 0.872340 (-3452 2425);
PAINT GREEN (-3452 2425);
DISPLAY INVISIBLE (-3452 2425);
FORCEADD TAP..1
(-3450 2525);
FORCEPROP 3 LASTPIN (-3500 2525) SIG_NAME M_B_CPU1_SB_DQ<31>
J 0
(-3490 2535);
DISPLAY 0.659574 (-3490 2535);
PAINT MONO (-3490 2535);
DISPLAY INVISIBLE (-3490 2535);
FORCEPROP 1 LASTPIN (-3500 2525) BN 31
J 0
(-3512 2533);
DISPLAY 0.489362 (-3512 2533);
PAINT GREEN (-3512 2533);
FORCEPROP 2 LAST CDS_LIB mstr_standard
J 0
(-3450 2525);
DISPLAY 0.723404 (-3450 2525);
PAINT MONO (-3450 2525);
DISPLAY INVISIBLE (-3450 2525);
FORCEPROP 1 LAST BODY_TYPE PLUMBING
J 0
(-3450 2575);
DISPLAY 0.872340 (-3450 2575);
PAINT GREEN (-3450 2575);
DISPLAY INVISIBLE (-3450 2575);
FORCEPROP 1 LAST HDL_TAP TRUE
J 0
(-3125 2400);
DISPLAY 0.872340 (-3125 2400);
DISPLAY INVISIBLE (-3125 2400);
FORCEPROP 1 LAST PATH I229
J 0
(-3452 2525);
DISPLAY 0.872340 (-3452 2525);
PAINT GREEN (-3452 2525);
DISPLAY INVISIBLE (-3452 2525);
FORCEADD TAP..1
(-3450 2275);
FORCEPROP 3 LASTPIN (-3500 2275) SIG_NAME M_B_CPU1_SA_CB<3>
J 0
(-3490 2285);
DISPLAY 0.659574 (-3490 2285);
PAINT MONO (-3490 2285);
DISPLAY INVISIBLE (-3490 2285);
FORCEPROP 1 LASTPIN (-3500 2275) BN 3
J 0
(-3512 2283);
DISPLAY 0.489362 (-3512 2283);
PAINT GREEN (-3512 2283);
FORCEPROP 2 LAST CDS_LIB mstr_standard
J 2
(-3450 2275);
DISPLAY 0.723404 (-3450 2275);
PAINT MONO (-3450 2275);
DISPLAY INVISIBLE (-3450 2275);
FORCEPROP 1 LAST BODY_TYPE PLUMBING
J 0
(-3450 2325);
DISPLAY 0.872340 (-3450 2325);
PAINT GREEN (-3450 2325);
DISPLAY INVISIBLE (-3450 2325);
FORCEPROP 1 LAST HDL_TAP TRUE
J 0
(-3125 2150);
DISPLAY 0.872340 (-3125 2150);
DISPLAY INVISIBLE (-3125 2150);
FORCEPROP 1 LAST PATH I230
J 0
(-3452 2275);
DISPLAY 0.872340 (-3452 2275);
PAINT GREEN (-3452 2275);
DISPLAY INVISIBLE (-3452 2275);
FORCEADD TAP..1
(-3450 2225);
FORCEPROP 3 LASTPIN (-3500 2225) SIG_NAME M_B_CPU1_SA_CB<4>
J 0
(-3490 2235);
DISPLAY 0.659574 (-3490 2235);
PAINT MONO (-3490 2235);
DISPLAY INVISIBLE (-3490 2235);
FORCEPROP 1 LASTPIN (-3500 2225) BN 4
J 0
(-3512 2233);
DISPLAY 0.489362 (-3512 2233);
PAINT GREEN (-3512 2233);
FORCEPROP 2 LAST CDS_LIB mstr_standard
J 2
(-3450 2225);
DISPLAY 0.723404 (-3450 2225);
PAINT MONO (-3450 2225);
DISPLAY INVISIBLE (-3450 2225);
FORCEPROP 1 LAST BODY_TYPE PLUMBING
J 0
(-3450 2275);
DISPLAY 0.872340 (-3450 2275);
PAINT GREEN (-3450 2275);
DISPLAY INVISIBLE (-3450 2275);
FORCEPROP 1 LAST HDL_TAP TRUE
J 0
(-3125 2100);
DISPLAY 0.872340 (-3125 2100);
DISPLAY INVISIBLE (-3125 2100);
FORCEPROP 1 LAST PATH I231
J 0
(-3452 2225);
DISPLAY 0.872340 (-3452 2225);
PAINT GREEN (-3452 2225);
DISPLAY INVISIBLE (-3452 2225);
FORCEADD TAP..1
(-3450 2175);
FORCEPROP 3 LASTPIN (-3500 2175) SIG_NAME M_B_CPU1_SA_CB<5>
J 0
(-3490 2185);
DISPLAY 0.659574 (-3490 2185);
PAINT MONO (-3490 2185);
DISPLAY INVISIBLE (-3490 2185);
FORCEPROP 1 LASTPIN (-3500 2175) BN 5
J 0
(-3512 2183);
DISPLAY 0.489362 (-3512 2183);
PAINT GREEN (-3512 2183);
FORCEPROP 2 LAST CDS_LIB mstr_standard
J 2
(-3450 2175);
DISPLAY 0.723404 (-3450 2175);
PAINT MONO (-3450 2175);
DISPLAY INVISIBLE (-3450 2175);
FORCEPROP 1 LAST BODY_TYPE PLUMBING
J 0
(-3450 2225);
DISPLAY 0.872340 (-3450 2225);
PAINT GREEN (-3450 2225);
DISPLAY INVISIBLE (-3450 2225);
FORCEPROP 1 LAST HDL_TAP TRUE
J 0
(-3125 2050);
DISPLAY 0.872340 (-3125 2050);
DISPLAY INVISIBLE (-3125 2050);
FORCEPROP 1 LAST PATH I232
J 0
(-3452 2175);
DISPLAY 0.872340 (-3452 2175);
PAINT GREEN (-3452 2175);
DISPLAY INVISIBLE (-3452 2175);
FORCEADD TAP..1
(-3450 2075);
FORCEPROP 3 LASTPIN (-3500 2075) SIG_NAME M_B_CPU1_SA_CB<7>
J 0
(-3490 2085);
DISPLAY 0.659574 (-3490 2085);
PAINT MONO (-3490 2085);
DISPLAY INVISIBLE (-3490 2085);
FORCEPROP 1 LASTPIN (-3500 2075) BN 7
J 0
(-3512 2083);
DISPLAY 0.489362 (-3512 2083);
PAINT GREEN (-3512 2083);
FORCEPROP 2 LAST CDS_LIB mstr_standard
J 2
(-3450 2075);
DISPLAY 0.723404 (-3450 2075);
PAINT MONO (-3450 2075);
DISPLAY INVISIBLE (-3450 2075);
FORCEPROP 1 LAST BODY_TYPE PLUMBING
J 0
(-3450 2125);
DISPLAY 0.872340 (-3450 2125);
PAINT GREEN (-3450 2125);
DISPLAY INVISIBLE (-3450 2125);
FORCEPROP 1 LAST HDL_TAP TRUE
J 0
(-3125 1950);
DISPLAY 0.872340 (-3125 1950);
DISPLAY INVISIBLE (-3125 1950);
FORCEPROP 1 LAST PATH I233
J 0
(-3452 2075);
DISPLAY 0.872340 (-3452 2075);
PAINT GREEN (-3452 2075);
DISPLAY INVISIBLE (-3452 2075);
FORCEADD TAP..1
(-3450 2125);
FORCEPROP 3 LASTPIN (-3500 2125) SIG_NAME M_B_CPU1_SA_CB<6>
J 0
(-3490 2135);
DISPLAY 0.659574 (-3490 2135);
PAINT MONO (-3490 2135);
DISPLAY INVISIBLE (-3490 2135);
FORCEPROP 1 LASTPIN (-3500 2125) BN 6
J 0
(-3512 2133);
DISPLAY 0.489362 (-3512 2133);
PAINT GREEN (-3512 2133);
FORCEPROP 2 LAST CDS_LIB mstr_standard
J 2
(-3450 2125);
DISPLAY 0.723404 (-3450 2125);
PAINT MONO (-3450 2125);
DISPLAY INVISIBLE (-3450 2125);
FORCEPROP 1 LAST BODY_TYPE PLUMBING
J 0
(-3450 2175);
DISPLAY 0.872340 (-3450 2175);
PAINT GREEN (-3450 2175);
DISPLAY INVISIBLE (-3450 2175);
FORCEPROP 1 LAST HDL_TAP TRUE
J 0
(-3125 2000);
DISPLAY 0.872340 (-3125 2000);
DISPLAY INVISIBLE (-3125 2000);
FORCEPROP 1 LAST PATH I234
J 0
(-3452 2125);
DISPLAY 0.872340 (-3452 2125);
PAINT GREEN (-3452 2125);
DISPLAY INVISIBLE (-3452 2125);
FORCEADD OFFPAGE..6
R 2
(-2850 2025);
FORCEPROP 2 LAST $XR0 99 
J 0
(-2636 2025);
DISPLAY 0.638298 (-2636 2025);
PAINT MONO (-2636 2025);
FORCEPROP 2 LAST CDS_LIB mstr_standard
J 2
(-2850 2025);
DISPLAY 0.723404 (-2850 2025);
PAINT MONO (-2850 2025);
DISPLAY INVISIBLE (-2850 2025);
FORCEPROP 1 LAST OFFPAGE TRUE
J 2
(-3175 1900);
DISPLAY 0.872340 (-3175 1900);
PAINT GREEN (-3175 1900);
DISPLAY INVISIBLE (-3175 1900);
FORCEPROP 1 LAST COMMENT_BODY TRUE
J 2
(-2950 1950);
DISPLAY 0.872340 (-2950 1950);
PAINT GREEN (-2950 1950);
DISPLAY INVISIBLE (-2950 1950);
FORCEPROP 2 LAST PATH I235
J 0
(-2625 2075);
DISPLAY 1.021277 (-2625 2075);
DISPLAY INVISIBLE (-2625 2075);
FORCEADD TAP..1
(-3450 1975);
FORCEPROP 3 LASTPIN (-3500 1975) SIG_NAME M_B_CPU1_SB_CB<0>
J 0
(-3490 1985);
DISPLAY 0.659574 (-3490 1985);
PAINT MONO (-3490 1985);
DISPLAY INVISIBLE (-3490 1985);
FORCEPROP 1 LASTPIN (-3500 1975) BN 0
J 0
(-3512 1983);
DISPLAY 0.489362 (-3512 1983);
PAINT GREEN (-3512 1983);
FORCEPROP 2 LAST CDS_LIB mstr_standard
J 2
(-3450 1975);
DISPLAY 0.723404 (-3450 1975);
PAINT MONO (-3450 1975);
DISPLAY INVISIBLE (-3450 1975);
FORCEPROP 1 LAST BODY_TYPE PLUMBING
J 0
(-3450 2025);
DISPLAY 0.872340 (-3450 2025);
PAINT GREEN (-3450 2025);
DISPLAY INVISIBLE (-3450 2025);
FORCEPROP 1 LAST HDL_TAP TRUE
J 0
(-3125 1850);
DISPLAY 0.872340 (-3125 1850);
DISPLAY INVISIBLE (-3125 1850);
FORCEPROP 1 LAST PATH I236
J 0
(-3452 1975);
DISPLAY 0.872340 (-3452 1975);
PAINT GREEN (-3452 1975);
DISPLAY INVISIBLE (-3452 1975);
FORCEADD TAP..1
(-3450 1925);
FORCEPROP 3 LASTPIN (-3500 1925) SIG_NAME M_B_CPU1_SB_CB<1>
J 0
(-3490 1935);
DISPLAY 0.659574 (-3490 1935);
PAINT MONO (-3490 1935);
DISPLAY INVISIBLE (-3490 1935);
FORCEPROP 1 LASTPIN (-3500 1925) BN 1
J 0
(-3512 1933);
DISPLAY 0.489362 (-3512 1933);
PAINT GREEN (-3512 1933);
FORCEPROP 2 LAST CDS_LIB mstr_standard
J 2
(-3450 1925);
DISPLAY 0.723404 (-3450 1925);
PAINT MONO (-3450 1925);
DISPLAY INVISIBLE (-3450 1925);
FORCEPROP 1 LAST BODY_TYPE PLUMBING
J 0
(-3450 1975);
DISPLAY 0.872340 (-3450 1975);
PAINT GREEN (-3450 1975);
DISPLAY INVISIBLE (-3450 1975);
FORCEPROP 1 LAST HDL_TAP TRUE
J 0
(-3125 1800);
DISPLAY 0.872340 (-3125 1800);
DISPLAY INVISIBLE (-3125 1800);
FORCEPROP 1 LAST PATH I237
J 0
(-3452 1925);
DISPLAY 0.872340 (-3452 1925);
PAINT GREEN (-3452 1925);
DISPLAY INVISIBLE (-3452 1925);
FORCEADD TAP..1
(-3450 1875);
FORCEPROP 3 LASTPIN (-3500 1875) SIG_NAME M_B_CPU1_SB_CB<2>
J 0
(-3490 1885);
DISPLAY 0.659574 (-3490 1885);
PAINT MONO (-3490 1885);
DISPLAY INVISIBLE (-3490 1885);
FORCEPROP 1 LASTPIN (-3500 1875) BN 2
J 0
(-3512 1883);
DISPLAY 0.489362 (-3512 1883);
PAINT GREEN (-3512 1883);
FORCEPROP 2 LAST CDS_LIB mstr_standard
J 2
(-3450 1875);
DISPLAY 0.723404 (-3450 1875);
PAINT MONO (-3450 1875);
DISPLAY INVISIBLE (-3450 1875);
FORCEPROP 1 LAST BODY_TYPE PLUMBING
J 0
(-3450 1925);
DISPLAY 0.872340 (-3450 1925);
PAINT GREEN (-3450 1925);
DISPLAY INVISIBLE (-3450 1925);
FORCEPROP 1 LAST HDL_TAP TRUE
J 0
(-3125 1750);
DISPLAY 0.872340 (-3125 1750);
DISPLAY INVISIBLE (-3125 1750);
FORCEPROP 1 LAST PATH I238
J 0
(-3452 1875);
DISPLAY 0.872340 (-3452 1875);
PAINT GREEN (-3452 1875);
DISPLAY INVISIBLE (-3452 1875);
FORCEADD TAP..1
(-3450 1825);
FORCEPROP 3 LASTPIN (-3500 1825) SIG_NAME M_B_CPU1_SB_CB<3>
J 0
(-3490 1835);
DISPLAY 0.659574 (-3490 1835);
PAINT MONO (-3490 1835);
DISPLAY INVISIBLE (-3490 1835);
FORCEPROP 1 LASTPIN (-3500 1825) BN 3
J 0
(-3512 1833);
DISPLAY 0.489362 (-3512 1833);
PAINT GREEN (-3512 1833);
FORCEPROP 2 LAST CDS_LIB mstr_standard
J 2
(-3450 1825);
DISPLAY 0.723404 (-3450 1825);
PAINT MONO (-3450 1825);
DISPLAY INVISIBLE (-3450 1825);
FORCEPROP 1 LAST BODY_TYPE PLUMBING
J 0
(-3450 1875);
DISPLAY 0.872340 (-3450 1875);
PAINT GREEN (-3450 1875);
DISPLAY INVISIBLE (-3450 1875);
FORCEPROP 1 LAST HDL_TAP TRUE
J 0
(-3125 1700);
DISPLAY 0.872340 (-3125 1700);
DISPLAY INVISIBLE (-3125 1700);
FORCEPROP 1 LAST PATH I239
J 0
(-3452 1825);
DISPLAY 0.872340 (-3452 1825);
PAINT GREEN (-3452 1825);
DISPLAY INVISIBLE (-3452 1825);
FORCEADD TAP..1
(-3450 1775);
FORCEPROP 3 LASTPIN (-3500 1775) SIG_NAME M_B_CPU1_SB_CB<4>
J 0
(-3490 1785);
DISPLAY 0.659574 (-3490 1785);
PAINT MONO (-3490 1785);
DISPLAY INVISIBLE (-3490 1785);
FORCEPROP 1 LASTPIN (-3500 1775) BN 4
J 0
(-3512 1783);
DISPLAY 0.489362 (-3512 1783);
PAINT GREEN (-3512 1783);
FORCEPROP 2 LAST CDS_LIB mstr_standard
J 2
(-3450 1775);
DISPLAY 0.723404 (-3450 1775);
PAINT MONO (-3450 1775);
DISPLAY INVISIBLE (-3450 1775);
FORCEPROP 1 LAST BODY_TYPE PLUMBING
J 0
(-3450 1825);
DISPLAY 0.872340 (-3450 1825);
PAINT GREEN (-3450 1825);
DISPLAY INVISIBLE (-3450 1825);
FORCEPROP 1 LAST HDL_TAP TRUE
J 0
(-3125 1650);
DISPLAY 0.872340 (-3125 1650);
DISPLAY INVISIBLE (-3125 1650);
FORCEPROP 1 LAST PATH I240
J 0
(-3452 1775);
DISPLAY 0.872340 (-3452 1775);
PAINT GREEN (-3452 1775);
DISPLAY INVISIBLE (-3452 1775);
FORCEADD TAP..1
(-3450 1725);
FORCEPROP 3 LASTPIN (-3500 1725) SIG_NAME M_B_CPU1_SB_CB<5>
J 0
(-3490 1735);
DISPLAY 0.659574 (-3490 1735);
PAINT MONO (-3490 1735);
DISPLAY INVISIBLE (-3490 1735);
FORCEPROP 1 LASTPIN (-3500 1725) BN 5
J 0
(-3512 1733);
DISPLAY 0.489362 (-3512 1733);
PAINT GREEN (-3512 1733);
FORCEPROP 2 LAST CDS_LIB mstr_standard
J 2
(-3450 1725);
DISPLAY 0.723404 (-3450 1725);
PAINT MONO (-3450 1725);
DISPLAY INVISIBLE (-3450 1725);
FORCEPROP 1 LAST BODY_TYPE PLUMBING
J 0
(-3450 1775);
DISPLAY 0.872340 (-3450 1775);
PAINT GREEN (-3450 1775);
DISPLAY INVISIBLE (-3450 1775);
FORCEPROP 1 LAST HDL_TAP TRUE
J 0
(-3125 1600);
DISPLAY 0.872340 (-3125 1600);
DISPLAY INVISIBLE (-3125 1600);
FORCEPROP 1 LAST PATH I241
J 0
(-3452 1725);
DISPLAY 0.872340 (-3452 1725);
PAINT GREEN (-3452 1725);
DISPLAY INVISIBLE (-3452 1725);
FORCEADD TAP..1
(-3450 1625);
FORCEPROP 3 LASTPIN (-3500 1625) SIG_NAME M_B_CPU1_SB_CB<7>
J 0
(-3490 1635);
DISPLAY 0.659574 (-3490 1635);
PAINT MONO (-3490 1635);
DISPLAY INVISIBLE (-3490 1635);
FORCEPROP 1 LASTPIN (-3500 1625) BN 7
J 0
(-3512 1633);
DISPLAY 0.489362 (-3512 1633);
PAINT GREEN (-3512 1633);
FORCEPROP 2 LAST CDS_LIB mstr_standard
J 2
(-3450 1625);
DISPLAY 0.723404 (-3450 1625);
PAINT MONO (-3450 1625);
DISPLAY INVISIBLE (-3450 1625);
FORCEPROP 1 LAST BODY_TYPE PLUMBING
J 0
(-3450 1675);
DISPLAY 0.872340 (-3450 1675);
PAINT GREEN (-3450 1675);
DISPLAY INVISIBLE (-3450 1675);
FORCEPROP 1 LAST HDL_TAP TRUE
J 0
(-3125 1500);
DISPLAY 0.872340 (-3125 1500);
DISPLAY INVISIBLE (-3125 1500);
FORCEPROP 1 LAST PATH I242
J 0
(-3452 1625);
DISPLAY 0.872340 (-3452 1625);
PAINT GREEN (-3452 1625);
DISPLAY INVISIBLE (-3452 1625);
FORCEADD TAP..1
(-3450 1675);
FORCEPROP 3 LASTPIN (-3500 1675) SIG_NAME M_B_CPU1_SB_CB<6>
J 0
(-3490 1685);
DISPLAY 0.659574 (-3490 1685);
PAINT MONO (-3490 1685);
DISPLAY INVISIBLE (-3490 1685);
FORCEPROP 1 LASTPIN (-3500 1675) BN 6
J 0
(-3512 1683);
DISPLAY 0.489362 (-3512 1683);
PAINT GREEN (-3512 1683);
FORCEPROP 2 LAST CDS_LIB mstr_standard
J 2
(-3450 1675);
DISPLAY 0.723404 (-3450 1675);
PAINT MONO (-3450 1675);
DISPLAY INVISIBLE (-3450 1675);
FORCEPROP 1 LAST BODY_TYPE PLUMBING
J 0
(-3450 1725);
DISPLAY 0.872340 (-3450 1725);
PAINT GREEN (-3450 1725);
DISPLAY INVISIBLE (-3450 1725);
FORCEPROP 1 LAST HDL_TAP TRUE
J 0
(-3125 1550);
DISPLAY 0.872340 (-3125 1550);
DISPLAY INVISIBLE (-3125 1550);
FORCEPROP 1 LAST PATH I243
J 0
(-3452 1675);
DISPLAY 0.872340 (-3452 1675);
PAINT GREEN (-3452 1675);
DISPLAY INVISIBLE (-3452 1675);
FORCEADD TAP..1
R 2
(-5875 6025);
FORCEPROP 3 LASTPIN (-5825 6025) SIG_NAME M_B_CPU1_SA_DQS_DP<0>
J 0
(-5815 6035);
DISPLAY 0.659574 (-5815 6035);
PAINT MONO (-5815 6035);
DISPLAY INVISIBLE (-5815 6035);
FORCEPROP 1 LASTPIN (-5825 6025) BN 0
J 2
(-5813 6033);
DISPLAY 0.489362 (-5813 6033);
PAINT GREEN (-5813 6033);
FORCEPROP 2 LAST CDS_LIB mstr_standard
J 2
(-5875 6025);
DISPLAY 0.723404 (-5875 6025);
PAINT MONO (-5875 6025);
DISPLAY INVISIBLE (-5875 6025);
FORCEPROP 1 LAST BODY_TYPE PLUMBING
J 2
(-5875 6075);
DISPLAY 0.872340 (-5875 6075);
PAINT GREEN (-5875 6075);
DISPLAY INVISIBLE (-5875 6075);
FORCEPROP 1 LAST HDL_TAP TRUE
J 2
(-6200 5900);
DISPLAY 0.872340 (-6200 5900);
DISPLAY INVISIBLE (-6200 5900);
FORCEPROP 1 LAST PATH I244
J 2
(-5873 6025);
DISPLAY 0.872340 (-5873 6025);
PAINT GREEN (-5873 6025);
DISPLAY INVISIBLE (-5873 6025);
FORCEADD TAP..1
R 2
(-5875 5925);
FORCEPROP 3 LASTPIN (-5825 5925) SIG_NAME M_B_CPU1_SA_DQS_DP<1>
J 0
(-5815 5935);
DISPLAY 0.659574 (-5815 5935);
PAINT MONO (-5815 5935);
DISPLAY INVISIBLE (-5815 5935);
FORCEPROP 1 LASTPIN (-5825 5925) BN 1
J 2
(-5813 5933);
DISPLAY 0.489362 (-5813 5933);
PAINT GREEN (-5813 5933);
FORCEPROP 2 LAST CDS_LIB mstr_standard
J 2
(-5875 5925);
DISPLAY 0.723404 (-5875 5925);
PAINT MONO (-5875 5925);
DISPLAY INVISIBLE (-5875 5925);
FORCEPROP 1 LAST BODY_TYPE PLUMBING
J 2
(-5875 5975);
DISPLAY 0.872340 (-5875 5975);
PAINT GREEN (-5875 5975);
DISPLAY INVISIBLE (-5875 5975);
FORCEPROP 1 LAST HDL_TAP TRUE
J 2
(-6200 5800);
DISPLAY 0.872340 (-6200 5800);
DISPLAY INVISIBLE (-6200 5800);
FORCEPROP 1 LAST PATH I245
J 2
(-5873 5925);
DISPLAY 0.872340 (-5873 5925);
PAINT GREEN (-5873 5925);
DISPLAY INVISIBLE (-5873 5925);
FORCEADD TAP..1
R 2
(-5875 5825);
FORCEPROP 3 LASTPIN (-5825 5825) SIG_NAME M_B_CPU1_SA_DQS_DP<2>
J 0
(-5815 5835);
DISPLAY 0.659574 (-5815 5835);
PAINT MONO (-5815 5835);
DISPLAY INVISIBLE (-5815 5835);
FORCEPROP 1 LASTPIN (-5825 5825) BN 2
J 2
(-5813 5833);
DISPLAY 0.489362 (-5813 5833);
PAINT GREEN (-5813 5833);
FORCEPROP 2 LAST CDS_LIB mstr_standard
J 2
(-5875 5825);
DISPLAY 0.723404 (-5875 5825);
PAINT MONO (-5875 5825);
DISPLAY INVISIBLE (-5875 5825);
FORCEPROP 1 LAST BODY_TYPE PLUMBING
J 2
(-5875 5875);
DISPLAY 0.872340 (-5875 5875);
PAINT GREEN (-5875 5875);
DISPLAY INVISIBLE (-5875 5875);
FORCEPROP 1 LAST HDL_TAP TRUE
J 2
(-6200 5700);
DISPLAY 0.872340 (-6200 5700);
DISPLAY INVISIBLE (-6200 5700);
FORCEPROP 1 LAST PATH I246
J 2
(-5873 5825);
DISPLAY 0.872340 (-5873 5825);
PAINT GREEN (-5873 5825);
DISPLAY INVISIBLE (-5873 5825);
FORCEADD TAP..1
R 2
(-5875 5725);
FORCEPROP 3 LASTPIN (-5825 5725) SIG_NAME M_B_CPU1_SA_DQS_DP<3>
J 0
(-5815 5735);
DISPLAY 0.659574 (-5815 5735);
PAINT MONO (-5815 5735);
DISPLAY INVISIBLE (-5815 5735);
FORCEPROP 1 LASTPIN (-5825 5725) BN 3
J 2
(-5813 5733);
DISPLAY 0.489362 (-5813 5733);
PAINT GREEN (-5813 5733);
FORCEPROP 2 LAST CDS_LIB mstr_standard
J 2
(-5875 5725);
DISPLAY 0.723404 (-5875 5725);
PAINT MONO (-5875 5725);
DISPLAY INVISIBLE (-5875 5725);
FORCEPROP 1 LAST BODY_TYPE PLUMBING
J 2
(-5875 5775);
DISPLAY 0.872340 (-5875 5775);
PAINT GREEN (-5875 5775);
DISPLAY INVISIBLE (-5875 5775);
FORCEPROP 1 LAST HDL_TAP TRUE
J 2
(-6200 5600);
DISPLAY 0.872340 (-6200 5600);
DISPLAY INVISIBLE (-6200 5600);
FORCEPROP 1 LAST PATH I247
J 2
(-5873 5725);
DISPLAY 0.872340 (-5873 5725);
PAINT GREEN (-5873 5725);
DISPLAY INVISIBLE (-5873 5725);
FORCEADD TAP..1
R 2
(-6075 5975);
FORCEPROP 3 LASTPIN (-6025 5975) SIG_NAME M_B_CPU1_SA_DQS_DN<0>
J 0
(-6015 5985);
DISPLAY 0.659574 (-6015 5985);
PAINT MONO (-6015 5985);
DISPLAY INVISIBLE (-6015 5985);
FORCEPROP 1 LASTPIN (-6025 5975) BN 0
J 2
(-6013 5983);
DISPLAY 0.489362 (-6013 5983);
PAINT GREEN (-6013 5983);
FORCEPROP 2 LAST CDS_LIB mstr_standard
J 2
(-6075 5975);
DISPLAY 0.723404 (-6075 5975);
PAINT MONO (-6075 5975);
DISPLAY INVISIBLE (-6075 5975);
FORCEPROP 1 LAST BODY_TYPE PLUMBING
J 2
(-6075 6025);
DISPLAY 0.872340 (-6075 6025);
PAINT GREEN (-6075 6025);
DISPLAY INVISIBLE (-6075 6025);
FORCEPROP 1 LAST HDL_TAP TRUE
J 2
(-6400 5850);
DISPLAY 0.872340 (-6400 5850);
DISPLAY INVISIBLE (-6400 5850);
FORCEPROP 1 LAST PATH I248
J 2
(-6073 5975);
DISPLAY 0.872340 (-6073 5975);
PAINT GREEN (-6073 5975);
DISPLAY INVISIBLE (-6073 5975);
FORCEADD TAP..1
R 2
(-6075 5875);
FORCEPROP 3 LASTPIN (-6025 5875) SIG_NAME M_B_CPU1_SA_DQS_DN<1>
J 0
(-6015 5885);
DISPLAY 0.659574 (-6015 5885);
PAINT MONO (-6015 5885);
DISPLAY INVISIBLE (-6015 5885);
FORCEPROP 1 LASTPIN (-6025 5875) BN 1
J 2
(-6013 5883);
DISPLAY 0.489362 (-6013 5883);
PAINT GREEN (-6013 5883);
FORCEPROP 2 LAST CDS_LIB mstr_standard
J 2
(-6075 5875);
DISPLAY 0.723404 (-6075 5875);
PAINT MONO (-6075 5875);
DISPLAY INVISIBLE (-6075 5875);
FORCEPROP 1 LAST BODY_TYPE PLUMBING
J 2
(-6075 5925);
DISPLAY 0.872340 (-6075 5925);
PAINT GREEN (-6075 5925);
DISPLAY INVISIBLE (-6075 5925);
FORCEPROP 1 LAST HDL_TAP TRUE
J 2
(-6400 5750);
DISPLAY 0.872340 (-6400 5750);
DISPLAY INVISIBLE (-6400 5750);
FORCEPROP 1 LAST PATH I249
J 2
(-6073 5875);
DISPLAY 0.872340 (-6073 5875);
PAINT GREEN (-6073 5875);
DISPLAY INVISIBLE (-6073 5875);
FORCEADD TAP..1
R 2
(-6075 5675);
FORCEPROP 3 LASTPIN (-6025 5675) SIG_NAME M_B_CPU1_SA_DQS_DN<3>
J 0
(-6015 5685);
DISPLAY 0.659574 (-6015 5685);
PAINT MONO (-6015 5685);
DISPLAY INVISIBLE (-6015 5685);
FORCEPROP 1 LASTPIN (-6025 5675) BN 3
J 2
(-6013 5683);
DISPLAY 0.489362 (-6013 5683);
PAINT GREEN (-6013 5683);
FORCEPROP 2 LAST CDS_LIB mstr_standard
J 2
(-6075 5675);
DISPLAY 0.723404 (-6075 5675);
PAINT MONO (-6075 5675);
DISPLAY INVISIBLE (-6075 5675);
FORCEPROP 1 LAST BODY_TYPE PLUMBING
J 2
(-6075 5725);
DISPLAY 0.872340 (-6075 5725);
PAINT GREEN (-6075 5725);
DISPLAY INVISIBLE (-6075 5725);
FORCEPROP 1 LAST HDL_TAP TRUE
J 2
(-6400 5550);
DISPLAY 0.872340 (-6400 5550);
DISPLAY INVISIBLE (-6400 5550);
FORCEPROP 1 LAST PATH I250
J 2
(-6073 5675);
DISPLAY 0.872340 (-6073 5675);
PAINT GREEN (-6073 5675);
DISPLAY INVISIBLE (-6073 5675);
FORCEADD TAP..1
R 2
(-6075 5775);
FORCEPROP 3 LASTPIN (-6025 5775) SIG_NAME M_B_CPU1_SA_DQS_DN<2>
J 0
(-6015 5785);
DISPLAY 0.659574 (-6015 5785);
PAINT MONO (-6015 5785);
DISPLAY INVISIBLE (-6015 5785);
FORCEPROP 1 LASTPIN (-6025 5775) BN 2
J 2
(-6013 5783);
DISPLAY 0.489362 (-6013 5783);
PAINT GREEN (-6013 5783);
FORCEPROP 2 LAST CDS_LIB mstr_standard
J 2
(-6075 5775);
DISPLAY 0.723404 (-6075 5775);
PAINT MONO (-6075 5775);
DISPLAY INVISIBLE (-6075 5775);
FORCEPROP 1 LAST BODY_TYPE PLUMBING
J 2
(-6075 5825);
DISPLAY 0.872340 (-6075 5825);
PAINT GREEN (-6075 5825);
DISPLAY INVISIBLE (-6075 5825);
FORCEPROP 1 LAST HDL_TAP TRUE
J 2
(-6400 5650);
DISPLAY 0.872340 (-6400 5650);
DISPLAY INVISIBLE (-6400 5650);
FORCEPROP 1 LAST PATH I251
J 2
(-6073 5775);
DISPLAY 0.872340 (-6073 5775);
PAINT GREEN (-6073 5775);
DISPLAY INVISIBLE (-6073 5775);
FORCEADD TAP..1
R 2
(-5875 5625);
FORCEPROP 3 LASTPIN (-5825 5625) SIG_NAME M_B_CPU1_SA_DQS_DP<4>
J 0
(-5815 5635);
DISPLAY 0.659574 (-5815 5635);
PAINT MONO (-5815 5635);
DISPLAY INVISIBLE (-5815 5635);
FORCEPROP 1 LASTPIN (-5825 5625) BN 4
J 2
(-5813 5633);
DISPLAY 0.489362 (-5813 5633);
PAINT GREEN (-5813 5633);
FORCEPROP 2 LAST CDS_LIB mstr_standard
J 2
(-5875 5625);
DISPLAY 0.723404 (-5875 5625);
PAINT MONO (-5875 5625);
DISPLAY INVISIBLE (-5875 5625);
FORCEPROP 1 LAST BODY_TYPE PLUMBING
J 2
(-5875 5675);
DISPLAY 0.872340 (-5875 5675);
PAINT GREEN (-5875 5675);
DISPLAY INVISIBLE (-5875 5675);
FORCEPROP 1 LAST HDL_TAP TRUE
J 2
(-6200 5500);
DISPLAY 0.872340 (-6200 5500);
DISPLAY INVISIBLE (-6200 5500);
FORCEPROP 1 LAST PATH I252
J 2
(-5873 5625);
DISPLAY 0.872340 (-5873 5625);
PAINT GREEN (-5873 5625);
DISPLAY INVISIBLE (-5873 5625);
FORCEADD TAP..1
R 2
(-5875 5525);
FORCEPROP 3 LASTPIN (-5825 5525) SIG_NAME M_B_CPU1_SA_DQS_DP<5>
J 0
(-5815 5535);
DISPLAY 0.659574 (-5815 5535);
PAINT MONO (-5815 5535);
DISPLAY INVISIBLE (-5815 5535);
FORCEPROP 1 LASTPIN (-5825 5525) BN 5
J 2
(-5813 5533);
DISPLAY 0.489362 (-5813 5533);
PAINT GREEN (-5813 5533);
FORCEPROP 2 LAST CDS_LIB mstr_standard
J 2
(-5875 5525);
DISPLAY 0.723404 (-5875 5525);
PAINT MONO (-5875 5525);
DISPLAY INVISIBLE (-5875 5525);
FORCEPROP 1 LAST BODY_TYPE PLUMBING
J 2
(-5875 5575);
DISPLAY 0.872340 (-5875 5575);
PAINT GREEN (-5875 5575);
DISPLAY INVISIBLE (-5875 5575);
FORCEPROP 1 LAST HDL_TAP TRUE
J 2
(-6200 5400);
DISPLAY 0.872340 (-6200 5400);
DISPLAY INVISIBLE (-6200 5400);
FORCEPROP 1 LAST PATH I253
J 2
(-5873 5525);
DISPLAY 0.872340 (-5873 5525);
PAINT GREEN (-5873 5525);
DISPLAY INVISIBLE (-5873 5525);
FORCEADD TAP..1
R 2
(-5875 5425);
FORCEPROP 3 LASTPIN (-5825 5425) SIG_NAME M_B_CPU1_SA_DQS_DP<6>
J 0
(-5815 5435);
DISPLAY 0.659574 (-5815 5435);
PAINT MONO (-5815 5435);
DISPLAY INVISIBLE (-5815 5435);
FORCEPROP 1 LASTPIN (-5825 5425) BN 6
J 2
(-5813 5433);
DISPLAY 0.489362 (-5813 5433);
PAINT GREEN (-5813 5433);
FORCEPROP 2 LAST CDS_LIB mstr_standard
J 2
(-5875 5425);
DISPLAY 0.723404 (-5875 5425);
PAINT MONO (-5875 5425);
DISPLAY INVISIBLE (-5875 5425);
FORCEPROP 1 LAST BODY_TYPE PLUMBING
J 2
(-5875 5475);
DISPLAY 0.872340 (-5875 5475);
PAINT GREEN (-5875 5475);
DISPLAY INVISIBLE (-5875 5475);
FORCEPROP 1 LAST HDL_TAP TRUE
J 2
(-6200 5300);
DISPLAY 0.872340 (-6200 5300);
DISPLAY INVISIBLE (-6200 5300);
FORCEPROP 1 LAST PATH I254
J 2
(-5873 5425);
DISPLAY 0.872340 (-5873 5425);
PAINT GREEN (-5873 5425);
DISPLAY INVISIBLE (-5873 5425);
FORCEADD TAP..1
R 2
(-5875 5325);
FORCEPROP 3 LASTPIN (-5825 5325) SIG_NAME M_B_CPU1_SA_DQS_DP<7>
J 0
(-5815 5335);
DISPLAY 0.659574 (-5815 5335);
PAINT MONO (-5815 5335);
DISPLAY INVISIBLE (-5815 5335);
FORCEPROP 1 LASTPIN (-5825 5325) BN 7
J 2
(-5813 5333);
DISPLAY 0.489362 (-5813 5333);
PAINT GREEN (-5813 5333);
FORCEPROP 2 LAST CDS_LIB mstr_standard
J 2
(-5875 5325);
DISPLAY 0.723404 (-5875 5325);
PAINT MONO (-5875 5325);
DISPLAY INVISIBLE (-5875 5325);
FORCEPROP 1 LAST BODY_TYPE PLUMBING
J 2
(-5875 5375);
DISPLAY 0.872340 (-5875 5375);
PAINT GREEN (-5875 5375);
DISPLAY INVISIBLE (-5875 5375);
FORCEPROP 1 LAST HDL_TAP TRUE
J 2
(-6200 5200);
DISPLAY 0.872340 (-6200 5200);
DISPLAY INVISIBLE (-6200 5200);
FORCEPROP 1 LAST PATH I255
J 2
(-5873 5325);
DISPLAY 0.872340 (-5873 5325);
PAINT GREEN (-5873 5325);
DISPLAY INVISIBLE (-5873 5325);
FORCEADD TAP..1
R 2
(-5875 5125);
FORCEPROP 3 LASTPIN (-5825 5125) SIG_NAME M_B_CPU1_SA_DQS_DP<9>
J 0
(-5815 5135);
DISPLAY 0.659574 (-5815 5135);
PAINT MONO (-5815 5135);
DISPLAY INVISIBLE (-5815 5135);
FORCEPROP 1 LASTPIN (-5825 5125) BN 9
J 2
(-5813 5133);
DISPLAY 0.489362 (-5813 5133);
PAINT GREEN (-5813 5133);
FORCEPROP 2 LAST CDS_LIB mstr_standard
J 2
(-5875 5125);
DISPLAY 0.723404 (-5875 5125);
PAINT MONO (-5875 5125);
DISPLAY INVISIBLE (-5875 5125);
FORCEPROP 1 LAST BODY_TYPE PLUMBING
J 2
(-5875 5175);
DISPLAY 0.872340 (-5875 5175);
PAINT GREEN (-5875 5175);
DISPLAY INVISIBLE (-5875 5175);
FORCEPROP 1 LAST HDL_TAP TRUE
J 2
(-6200 5000);
DISPLAY 0.872340 (-6200 5000);
DISPLAY INVISIBLE (-6200 5000);
FORCEPROP 1 LAST PATH I256
J 2
(-5873 5125);
DISPLAY 0.872340 (-5873 5125);
PAINT GREEN (-5873 5125);
DISPLAY INVISIBLE (-5873 5125);
FORCEADD TAP..1
R 2
(-5875 5225);
FORCEPROP 3 LASTPIN (-5825 5225) SIG_NAME M_B_CPU1_SA_DQS_DP<8>
J 0
(-5815 5235);
DISPLAY 0.659574 (-5815 5235);
PAINT MONO (-5815 5235);
DISPLAY INVISIBLE (-5815 5235);
FORCEPROP 1 LASTPIN (-5825 5225) BN 8
J 2
(-5813 5233);
DISPLAY 0.489362 (-5813 5233);
PAINT GREEN (-5813 5233);
FORCEPROP 2 LAST CDS_LIB mstr_standard
J 2
(-5875 5225);
DISPLAY 0.723404 (-5875 5225);
PAINT MONO (-5875 5225);
DISPLAY INVISIBLE (-5875 5225);
FORCEPROP 1 LAST BODY_TYPE PLUMBING
J 2
(-5875 5275);
DISPLAY 0.872340 (-5875 5275);
PAINT GREEN (-5875 5275);
DISPLAY INVISIBLE (-5875 5275);
FORCEPROP 1 LAST HDL_TAP TRUE
J 2
(-6200 5100);
DISPLAY 0.872340 (-6200 5100);
DISPLAY INVISIBLE (-6200 5100);
FORCEPROP 1 LAST PATH I257
J 2
(-5873 5225);
DISPLAY 0.872340 (-5873 5225);
PAINT GREEN (-5873 5225);
DISPLAY INVISIBLE (-5873 5225);
FORCEADD TAP..1
R 2
(-6075 5475);
FORCEPROP 3 LASTPIN (-6025 5475) SIG_NAME M_B_CPU1_SA_DQS_DN<5>
J 0
(-6015 5485);
DISPLAY 0.659574 (-6015 5485);
PAINT MONO (-6015 5485);
DISPLAY INVISIBLE (-6015 5485);
FORCEPROP 1 LASTPIN (-6025 5475) BN 5
J 2
(-6013 5483);
DISPLAY 0.489362 (-6013 5483);
PAINT GREEN (-6013 5483);
FORCEPROP 2 LAST CDS_LIB mstr_standard
J 2
(-6075 5475);
DISPLAY 0.723404 (-6075 5475);
PAINT MONO (-6075 5475);
DISPLAY INVISIBLE (-6075 5475);
FORCEPROP 1 LAST BODY_TYPE PLUMBING
J 2
(-6075 5525);
DISPLAY 0.872340 (-6075 5525);
PAINT GREEN (-6075 5525);
DISPLAY INVISIBLE (-6075 5525);
FORCEPROP 1 LAST HDL_TAP TRUE
J 2
(-6400 5350);
DISPLAY 0.872340 (-6400 5350);
DISPLAY INVISIBLE (-6400 5350);
FORCEPROP 1 LAST PATH I258
J 2
(-6073 5475);
DISPLAY 0.872340 (-6073 5475);
PAINT GREEN (-6073 5475);
DISPLAY INVISIBLE (-6073 5475);
FORCEADD TAP..1
R 2
(-6075 5575);
FORCEPROP 3 LASTPIN (-6025 5575) SIG_NAME M_B_CPU1_SA_DQS_DN<4>
J 0
(-6015 5585);
DISPLAY 0.659574 (-6015 5585);
PAINT MONO (-6015 5585);
DISPLAY INVISIBLE (-6015 5585);
FORCEPROP 1 LASTPIN (-6025 5575) BN 4
J 2
(-6013 5583);
DISPLAY 0.489362 (-6013 5583);
PAINT GREEN (-6013 5583);
FORCEPROP 2 LAST CDS_LIB mstr_standard
J 2
(-6075 5575);
DISPLAY 0.723404 (-6075 5575);
PAINT MONO (-6075 5575);
DISPLAY INVISIBLE (-6075 5575);
FORCEPROP 1 LAST BODY_TYPE PLUMBING
J 2
(-6075 5625);
DISPLAY 0.872340 (-6075 5625);
PAINT GREEN (-6075 5625);
DISPLAY INVISIBLE (-6075 5625);
FORCEPROP 1 LAST HDL_TAP TRUE
J 2
(-6400 5450);
DISPLAY 0.872340 (-6400 5450);
DISPLAY INVISIBLE (-6400 5450);
FORCEPROP 1 LAST PATH I259
J 2
(-6073 5575);
DISPLAY 0.872340 (-6073 5575);
PAINT GREEN (-6073 5575);
DISPLAY INVISIBLE (-6073 5575);
FORCEADD TAP..1
R 2
(-6075 5375);
FORCEPROP 3 LASTPIN (-6025 5375) SIG_NAME M_B_CPU1_SA_DQS_DN<6>
J 0
(-6015 5385);
DISPLAY 0.659574 (-6015 5385);
PAINT MONO (-6015 5385);
DISPLAY INVISIBLE (-6015 5385);
FORCEPROP 1 LASTPIN (-6025 5375) BN 6
J 2
(-6013 5383);
DISPLAY 0.489362 (-6013 5383);
PAINT GREEN (-6013 5383);
FORCEPROP 2 LAST CDS_LIB mstr_standard
J 2
(-6075 5375);
DISPLAY 0.723404 (-6075 5375);
PAINT MONO (-6075 5375);
DISPLAY INVISIBLE (-6075 5375);
FORCEPROP 1 LAST BODY_TYPE PLUMBING
J 2
(-6075 5425);
DISPLAY 0.872340 (-6075 5425);
PAINT GREEN (-6075 5425);
DISPLAY INVISIBLE (-6075 5425);
FORCEPROP 1 LAST HDL_TAP TRUE
J 2
(-6400 5250);
DISPLAY 0.872340 (-6400 5250);
DISPLAY INVISIBLE (-6400 5250);
FORCEPROP 1 LAST PATH I260
J 2
(-6073 5375);
DISPLAY 0.872340 (-6073 5375);
PAINT GREEN (-6073 5375);
DISPLAY INVISIBLE (-6073 5375);
FORCEADD TAP..1
R 2
(-6075 5275);
FORCEPROP 3 LASTPIN (-6025 5275) SIG_NAME M_B_CPU1_SA_DQS_DN<7>
J 0
(-6015 5285);
DISPLAY 0.659574 (-6015 5285);
PAINT MONO (-6015 5285);
DISPLAY INVISIBLE (-6015 5285);
FORCEPROP 1 LASTPIN (-6025 5275) BN 7
J 2
(-6013 5283);
DISPLAY 0.489362 (-6013 5283);
PAINT GREEN (-6013 5283);
FORCEPROP 2 LAST CDS_LIB mstr_standard
J 2
(-6075 5275);
DISPLAY 0.723404 (-6075 5275);
PAINT MONO (-6075 5275);
DISPLAY INVISIBLE (-6075 5275);
FORCEPROP 1 LAST BODY_TYPE PLUMBING
J 2
(-6075 5325);
DISPLAY 0.872340 (-6075 5325);
PAINT GREEN (-6075 5325);
DISPLAY INVISIBLE (-6075 5325);
FORCEPROP 1 LAST HDL_TAP TRUE
J 2
(-6400 5150);
DISPLAY 0.872340 (-6400 5150);
DISPLAY INVISIBLE (-6400 5150);
FORCEPROP 1 LAST PATH I261
J 2
(-6073 5275);
DISPLAY 0.872340 (-6073 5275);
PAINT GREEN (-6073 5275);
DISPLAY INVISIBLE (-6073 5275);
FORCEADD TAP..1
R 2
(-6075 5175);
FORCEPROP 3 LASTPIN (-6025 5175) SIG_NAME M_B_CPU1_SA_DQS_DN<8>
J 0
(-6015 5185);
DISPLAY 0.659574 (-6015 5185);
PAINT MONO (-6015 5185);
DISPLAY INVISIBLE (-6015 5185);
FORCEPROP 1 LASTPIN (-6025 5175) BN 8
J 2
(-6013 5183);
DISPLAY 0.489362 (-6013 5183);
PAINT GREEN (-6013 5183);
FORCEPROP 2 LAST CDS_LIB mstr_standard
J 2
(-6075 5175);
DISPLAY 0.723404 (-6075 5175);
PAINT MONO (-6075 5175);
DISPLAY INVISIBLE (-6075 5175);
FORCEPROP 1 LAST BODY_TYPE PLUMBING
J 2
(-6075 5225);
DISPLAY 0.872340 (-6075 5225);
PAINT GREEN (-6075 5225);
DISPLAY INVISIBLE (-6075 5225);
FORCEPROP 1 LAST HDL_TAP TRUE
J 2
(-6400 5050);
DISPLAY 0.872340 (-6400 5050);
DISPLAY INVISIBLE (-6400 5050);
FORCEPROP 1 LAST PATH I262
J 2
(-6073 5175);
DISPLAY 0.872340 (-6073 5175);
PAINT GREEN (-6073 5175);
DISPLAY INVISIBLE (-6073 5175);
FORCEADD TAP..1
R 2
(-5875 4975);
FORCEPROP 3 LASTPIN (-5825 4975) SIG_NAME M_B_CPU1_SB_DQS_DP<0>
J 0
(-5815 4985);
DISPLAY 0.659574 (-5815 4985);
PAINT MONO (-5815 4985);
DISPLAY INVISIBLE (-5815 4985);
FORCEPROP 1 LASTPIN (-5825 4975) BN 0
J 2
(-5813 4983);
DISPLAY 0.489362 (-5813 4983);
PAINT GREEN (-5813 4983);
FORCEPROP 2 LAST CDS_LIB mstr_standard
J 2
(-5875 4975);
DISPLAY 0.723404 (-5875 4975);
PAINT MONO (-5875 4975);
DISPLAY INVISIBLE (-5875 4975);
FORCEPROP 1 LAST BODY_TYPE PLUMBING
J 2
(-5875 5025);
DISPLAY 0.872340 (-5875 5025);
PAINT GREEN (-5875 5025);
DISPLAY INVISIBLE (-5875 5025);
FORCEPROP 1 LAST HDL_TAP TRUE
J 2
(-6200 4850);
DISPLAY 0.872340 (-6200 4850);
DISPLAY INVISIBLE (-6200 4850);
FORCEPROP 1 LAST PATH I263
J 2
(-5873 4975);
DISPLAY 0.872340 (-5873 4975);
PAINT GREEN (-5873 4975);
DISPLAY INVISIBLE (-5873 4975);
FORCEADD TAP..1
R 2
(-5875 4875);
FORCEPROP 3 LASTPIN (-5825 4875) SIG_NAME M_B_CPU1_SB_DQS_DP<1>
J 0
(-5815 4885);
DISPLAY 0.659574 (-5815 4885);
PAINT MONO (-5815 4885);
DISPLAY INVISIBLE (-5815 4885);
FORCEPROP 1 LASTPIN (-5825 4875) BN 1
J 2
(-5813 4883);
DISPLAY 0.489362 (-5813 4883);
PAINT GREEN (-5813 4883);
FORCEPROP 2 LAST CDS_LIB mstr_standard
J 2
(-5875 4875);
DISPLAY 0.723404 (-5875 4875);
PAINT MONO (-5875 4875);
DISPLAY INVISIBLE (-5875 4875);
FORCEPROP 1 LAST BODY_TYPE PLUMBING
J 2
(-5875 4925);
DISPLAY 0.872340 (-5875 4925);
PAINT GREEN (-5875 4925);
DISPLAY INVISIBLE (-5875 4925);
FORCEPROP 1 LAST HDL_TAP TRUE
J 2
(-6200 4750);
DISPLAY 0.872340 (-6200 4750);
DISPLAY INVISIBLE (-6200 4750);
FORCEPROP 1 LAST PATH I264
J 2
(-5873 4875);
DISPLAY 0.872340 (-5873 4875);
PAINT GREEN (-5873 4875);
DISPLAY INVISIBLE (-5873 4875);
FORCEADD TAP..1
R 2
(-5875 4775);
FORCEPROP 3 LASTPIN (-5825 4775) SIG_NAME M_B_CPU1_SB_DQS_DP<2>
J 0
(-5815 4785);
DISPLAY 0.659574 (-5815 4785);
PAINT MONO (-5815 4785);
DISPLAY INVISIBLE (-5815 4785);
FORCEPROP 1 LASTPIN (-5825 4775) BN 2
J 2
(-5813 4783);
DISPLAY 0.489362 (-5813 4783);
PAINT GREEN (-5813 4783);
FORCEPROP 2 LAST CDS_LIB mstr_standard
J 2
(-5875 4775);
DISPLAY 0.723404 (-5875 4775);
PAINT MONO (-5875 4775);
DISPLAY INVISIBLE (-5875 4775);
FORCEPROP 1 LAST BODY_TYPE PLUMBING
J 2
(-5875 4825);
DISPLAY 0.872340 (-5875 4825);
PAINT GREEN (-5875 4825);
DISPLAY INVISIBLE (-5875 4825);
FORCEPROP 1 LAST HDL_TAP TRUE
J 2
(-6200 4650);
DISPLAY 0.872340 (-6200 4650);
DISPLAY INVISIBLE (-6200 4650);
FORCEPROP 1 LAST PATH I265
J 2
(-5873 4775);
DISPLAY 0.872340 (-5873 4775);
PAINT GREEN (-5873 4775);
DISPLAY INVISIBLE (-5873 4775);
FORCEADD TAP..1
R 2
(-5875 4675);
FORCEPROP 3 LASTPIN (-5825 4675) SIG_NAME M_B_CPU1_SB_DQS_DP<3>
J 0
(-5815 4685);
DISPLAY 0.659574 (-5815 4685);
PAINT MONO (-5815 4685);
DISPLAY INVISIBLE (-5815 4685);
FORCEPROP 1 LASTPIN (-5825 4675) BN 3
J 2
(-5813 4683);
DISPLAY 0.489362 (-5813 4683);
PAINT GREEN (-5813 4683);
FORCEPROP 2 LAST CDS_LIB mstr_standard
J 2
(-5875 4675);
DISPLAY 0.723404 (-5875 4675);
PAINT MONO (-5875 4675);
DISPLAY INVISIBLE (-5875 4675);
FORCEPROP 1 LAST BODY_TYPE PLUMBING
J 2
(-5875 4725);
DISPLAY 0.872340 (-5875 4725);
PAINT GREEN (-5875 4725);
DISPLAY INVISIBLE (-5875 4725);
FORCEPROP 1 LAST HDL_TAP TRUE
J 2
(-6200 4550);
DISPLAY 0.872340 (-6200 4550);
DISPLAY INVISIBLE (-6200 4550);
FORCEPROP 1 LAST PATH I266
J 2
(-5873 4675);
DISPLAY 0.872340 (-5873 4675);
PAINT GREEN (-5873 4675);
DISPLAY INVISIBLE (-5873 4675);
FORCEADD TAP..1
R 2
(-6075 4925);
FORCEPROP 3 LASTPIN (-6025 4925) SIG_NAME M_B_CPU1_SB_DQS_DN<0>
J 0
(-6015 4935);
DISPLAY 0.659574 (-6015 4935);
PAINT MONO (-6015 4935);
DISPLAY INVISIBLE (-6015 4935);
FORCEPROP 1 LASTPIN (-6025 4925) BN 0
J 2
(-6013 4933);
DISPLAY 0.489362 (-6013 4933);
PAINT GREEN (-6013 4933);
FORCEPROP 2 LAST CDS_LIB mstr_standard
J 2
(-6075 4925);
DISPLAY 0.723404 (-6075 4925);
PAINT MONO (-6075 4925);
DISPLAY INVISIBLE (-6075 4925);
FORCEPROP 1 LAST BODY_TYPE PLUMBING
J 2
(-6075 4975);
DISPLAY 0.872340 (-6075 4975);
PAINT GREEN (-6075 4975);
DISPLAY INVISIBLE (-6075 4975);
FORCEPROP 1 LAST HDL_TAP TRUE
J 2
(-6400 4800);
DISPLAY 0.872340 (-6400 4800);
DISPLAY INVISIBLE (-6400 4800);
FORCEPROP 1 LAST PATH I267
J 2
(-6073 4925);
DISPLAY 0.872340 (-6073 4925);
PAINT GREEN (-6073 4925);
DISPLAY INVISIBLE (-6073 4925);
FORCEADD TAP..1
R 2
(-6075 5075);
FORCEPROP 3 LASTPIN (-6025 5075) SIG_NAME M_B_CPU1_SA_DQS_DN<9>
J 0
(-6015 5085);
DISPLAY 0.659574 (-6015 5085);
PAINT MONO (-6015 5085);
DISPLAY INVISIBLE (-6015 5085);
FORCEPROP 1 LASTPIN (-6025 5075) BN 9
J 2
(-6013 5083);
DISPLAY 0.489362 (-6013 5083);
PAINT GREEN (-6013 5083);
FORCEPROP 2 LAST CDS_LIB mstr_standard
J 2
(-6075 5075);
DISPLAY 0.723404 (-6075 5075);
PAINT MONO (-6075 5075);
DISPLAY INVISIBLE (-6075 5075);
FORCEPROP 1 LAST BODY_TYPE PLUMBING
J 2
(-6075 5125);
DISPLAY 0.872340 (-6075 5125);
PAINT GREEN (-6075 5125);
DISPLAY INVISIBLE (-6075 5125);
FORCEPROP 1 LAST HDL_TAP TRUE
J 2
(-6400 4950);
DISPLAY 0.872340 (-6400 4950);
DISPLAY INVISIBLE (-6400 4950);
FORCEPROP 1 LAST PATH I268
J 2
(-6073 5075);
DISPLAY 0.872340 (-6073 5075);
PAINT GREEN (-6073 5075);
DISPLAY INVISIBLE (-6073 5075);
FORCEADD TAP..1
R 2
(-6075 4825);
FORCEPROP 3 LASTPIN (-6025 4825) SIG_NAME M_B_CPU1_SB_DQS_DN<1>
J 0
(-6015 4835);
DISPLAY 0.659574 (-6015 4835);
PAINT MONO (-6015 4835);
DISPLAY INVISIBLE (-6015 4835);
FORCEPROP 1 LASTPIN (-6025 4825) BN 1
J 2
(-6013 4833);
DISPLAY 0.489362 (-6013 4833);
PAINT GREEN (-6013 4833);
FORCEPROP 2 LAST CDS_LIB mstr_standard
J 2
(-6075 4825);
DISPLAY 0.723404 (-6075 4825);
PAINT MONO (-6075 4825);
DISPLAY INVISIBLE (-6075 4825);
FORCEPROP 1 LAST BODY_TYPE PLUMBING
J 2
(-6075 4875);
DISPLAY 0.872340 (-6075 4875);
PAINT GREEN (-6075 4875);
DISPLAY INVISIBLE (-6075 4875);
FORCEPROP 1 LAST HDL_TAP TRUE
J 2
(-6400 4700);
DISPLAY 0.872340 (-6400 4700);
DISPLAY INVISIBLE (-6400 4700);
FORCEPROP 1 LAST PATH I269
J 2
(-6073 4825);
DISPLAY 0.872340 (-6073 4825);
PAINT GREEN (-6073 4825);
DISPLAY INVISIBLE (-6073 4825);
FORCEADD TAP..1
R 2
(-6075 4725);
FORCEPROP 3 LASTPIN (-6025 4725) SIG_NAME M_B_CPU1_SB_DQS_DN<2>
J 0
(-6015 4735);
DISPLAY 0.659574 (-6015 4735);
PAINT MONO (-6015 4735);
DISPLAY INVISIBLE (-6015 4735);
FORCEPROP 1 LASTPIN (-6025 4725) BN 2
J 2
(-6013 4733);
DISPLAY 0.489362 (-6013 4733);
PAINT GREEN (-6013 4733);
FORCEPROP 2 LAST CDS_LIB mstr_standard
J 2
(-6075 4725);
DISPLAY 0.723404 (-6075 4725);
PAINT MONO (-6075 4725);
DISPLAY INVISIBLE (-6075 4725);
FORCEPROP 1 LAST BODY_TYPE PLUMBING
J 2
(-6075 4775);
DISPLAY 0.872340 (-6075 4775);
PAINT GREEN (-6075 4775);
DISPLAY INVISIBLE (-6075 4775);
FORCEPROP 1 LAST HDL_TAP TRUE
J 2
(-6400 4600);
DISPLAY 0.872340 (-6400 4600);
DISPLAY INVISIBLE (-6400 4600);
FORCEPROP 1 LAST PATH I270
J 2
(-6073 4725);
DISPLAY 0.872340 (-6073 4725);
PAINT GREEN (-6073 4725);
DISPLAY INVISIBLE (-6073 4725);
FORCEADD TAP..1
R 2
(-6075 4625);
FORCEPROP 3 LASTPIN (-6025 4625) SIG_NAME M_B_CPU1_SB_DQS_DN<3>
J 0
(-6015 4635);
DISPLAY 0.659574 (-6015 4635);
PAINT MONO (-6015 4635);
DISPLAY INVISIBLE (-6015 4635);
FORCEPROP 1 LASTPIN (-6025 4625) BN 3
J 2
(-6013 4633);
DISPLAY 0.489362 (-6013 4633);
PAINT GREEN (-6013 4633);
FORCEPROP 2 LAST CDS_LIB mstr_standard
J 2
(-6075 4625);
DISPLAY 0.723404 (-6075 4625);
PAINT MONO (-6075 4625);
DISPLAY INVISIBLE (-6075 4625);
FORCEPROP 1 LAST BODY_TYPE PLUMBING
J 2
(-6075 4675);
DISPLAY 0.872340 (-6075 4675);
PAINT GREEN (-6075 4675);
DISPLAY INVISIBLE (-6075 4675);
FORCEPROP 1 LAST HDL_TAP TRUE
J 2
(-6400 4500);
DISPLAY 0.872340 (-6400 4500);
DISPLAY INVISIBLE (-6400 4500);
FORCEPROP 1 LAST PATH I271
J 2
(-6073 4625);
DISPLAY 0.872340 (-6073 4625);
PAINT GREEN (-6073 4625);
DISPLAY INVISIBLE (-6073 4625);
FORCEADD TAP..1
R 2
(-5875 4575);
FORCEPROP 3 LASTPIN (-5825 4575) SIG_NAME M_B_CPU1_SB_DQS_DP<4>
J 0
(-5815 4585);
DISPLAY 0.659574 (-5815 4585);
PAINT MONO (-5815 4585);
DISPLAY INVISIBLE (-5815 4585);
FORCEPROP 1 LASTPIN (-5825 4575) BN 4
J 2
(-5813 4583);
DISPLAY 0.489362 (-5813 4583);
PAINT GREEN (-5813 4583);
FORCEPROP 2 LAST CDS_LIB mstr_standard
J 2
(-5875 4575);
DISPLAY 0.723404 (-5875 4575);
PAINT MONO (-5875 4575);
DISPLAY INVISIBLE (-5875 4575);
FORCEPROP 1 LAST BODY_TYPE PLUMBING
J 2
(-5875 4625);
DISPLAY 0.872340 (-5875 4625);
PAINT GREEN (-5875 4625);
DISPLAY INVISIBLE (-5875 4625);
FORCEPROP 1 LAST HDL_TAP TRUE
J 2
(-6200 4450);
DISPLAY 0.872340 (-6200 4450);
DISPLAY INVISIBLE (-6200 4450);
FORCEPROP 1 LAST PATH I272
J 2
(-5873 4575);
DISPLAY 0.872340 (-5873 4575);
PAINT GREEN (-5873 4575);
DISPLAY INVISIBLE (-5873 4575);
FORCEADD TAP..1
R 2
(-5875 4375);
FORCEPROP 3 LASTPIN (-5825 4375) SIG_NAME M_B_CPU1_SB_DQS_DP<6>
J 0
(-5815 4385);
DISPLAY 0.659574 (-5815 4385);
PAINT MONO (-5815 4385);
DISPLAY INVISIBLE (-5815 4385);
FORCEPROP 1 LASTPIN (-5825 4375) BN 6
J 2
(-5813 4383);
DISPLAY 0.489362 (-5813 4383);
PAINT GREEN (-5813 4383);
FORCEPROP 2 LAST CDS_LIB mstr_standard
J 2
(-5875 4375);
DISPLAY 0.723404 (-5875 4375);
PAINT MONO (-5875 4375);
DISPLAY INVISIBLE (-5875 4375);
FORCEPROP 1 LAST BODY_TYPE PLUMBING
J 2
(-5875 4425);
DISPLAY 0.872340 (-5875 4425);
PAINT GREEN (-5875 4425);
DISPLAY INVISIBLE (-5875 4425);
FORCEPROP 1 LAST HDL_TAP TRUE
J 2
(-6200 4250);
DISPLAY 0.872340 (-6200 4250);
DISPLAY INVISIBLE (-6200 4250);
FORCEPROP 1 LAST PATH I273
J 2
(-5873 4375);
DISPLAY 0.872340 (-5873 4375);
PAINT GREEN (-5873 4375);
DISPLAY INVISIBLE (-5873 4375);
FORCEADD TAP..1
R 2
(-5875 4475);
FORCEPROP 3 LASTPIN (-5825 4475) SIG_NAME M_B_CPU1_SB_DQS_DP<5>
J 0
(-5815 4485);
DISPLAY 0.659574 (-5815 4485);
PAINT MONO (-5815 4485);
DISPLAY INVISIBLE (-5815 4485);
FORCEPROP 1 LASTPIN (-5825 4475) BN 5
J 2
(-5813 4483);
DISPLAY 0.489362 (-5813 4483);
PAINT GREEN (-5813 4483);
FORCEPROP 2 LAST CDS_LIB mstr_standard
J 2
(-5875 4475);
DISPLAY 0.723404 (-5875 4475);
PAINT MONO (-5875 4475);
DISPLAY INVISIBLE (-5875 4475);
FORCEPROP 1 LAST BODY_TYPE PLUMBING
J 2
(-5875 4525);
DISPLAY 0.872340 (-5875 4525);
PAINT GREEN (-5875 4525);
DISPLAY INVISIBLE (-5875 4525);
FORCEPROP 1 LAST HDL_TAP TRUE
J 2
(-6200 4350);
DISPLAY 0.872340 (-6200 4350);
DISPLAY INVISIBLE (-6200 4350);
FORCEPROP 1 LAST PATH I274
J 2
(-5873 4475);
DISPLAY 0.872340 (-5873 4475);
PAINT GREEN (-5873 4475);
DISPLAY INVISIBLE (-5873 4475);
FORCEADD TAP..1
R 2
(-5875 4275);
FORCEPROP 3 LASTPIN (-5825 4275) SIG_NAME M_B_CPU1_SB_DQS_DP<7>
J 0
(-5815 4285);
DISPLAY 0.659574 (-5815 4285);
PAINT MONO (-5815 4285);
DISPLAY INVISIBLE (-5815 4285);
FORCEPROP 1 LASTPIN (-5825 4275) BN 7
J 2
(-5813 4283);
DISPLAY 0.489362 (-5813 4283);
PAINT GREEN (-5813 4283);
FORCEPROP 2 LAST CDS_LIB mstr_standard
J 2
(-5875 4275);
DISPLAY 0.723404 (-5875 4275);
PAINT MONO (-5875 4275);
DISPLAY INVISIBLE (-5875 4275);
FORCEPROP 1 LAST BODY_TYPE PLUMBING
J 2
(-5875 4325);
DISPLAY 0.872340 (-5875 4325);
PAINT GREEN (-5875 4325);
DISPLAY INVISIBLE (-5875 4325);
FORCEPROP 1 LAST HDL_TAP TRUE
J 2
(-6200 4150);
DISPLAY 0.872340 (-6200 4150);
DISPLAY INVISIBLE (-6200 4150);
FORCEPROP 1 LAST PATH I275
J 2
(-5873 4275);
DISPLAY 0.872340 (-5873 4275);
PAINT GREEN (-5873 4275);
DISPLAY INVISIBLE (-5873 4275);
FORCEADD TAP..1
R 2
(-5875 4175);
FORCEPROP 3 LASTPIN (-5825 4175) SIG_NAME M_B_CPU1_SB_DQS_DP<8>
J 0
(-5815 4185);
DISPLAY 0.659574 (-5815 4185);
PAINT MONO (-5815 4185);
DISPLAY INVISIBLE (-5815 4185);
FORCEPROP 1 LASTPIN (-5825 4175) BN 8
J 2
(-5813 4183);
DISPLAY 0.489362 (-5813 4183);
PAINT GREEN (-5813 4183);
FORCEPROP 2 LAST CDS_LIB mstr_standard
J 2
(-5875 4175);
DISPLAY 0.723404 (-5875 4175);
PAINT MONO (-5875 4175);
DISPLAY INVISIBLE (-5875 4175);
FORCEPROP 1 LAST BODY_TYPE PLUMBING
J 2
(-5875 4225);
DISPLAY 0.872340 (-5875 4225);
PAINT GREEN (-5875 4225);
DISPLAY INVISIBLE (-5875 4225);
FORCEPROP 1 LAST HDL_TAP TRUE
J 2
(-6200 4050);
DISPLAY 0.872340 (-6200 4050);
DISPLAY INVISIBLE (-6200 4050);
FORCEPROP 1 LAST PATH I276
J 2
(-5873 4175);
DISPLAY 0.872340 (-5873 4175);
PAINT GREEN (-5873 4175);
DISPLAY INVISIBLE (-5873 4175);
FORCEADD TAP..1
R 2
(-6075 4425);
FORCEPROP 3 LASTPIN (-6025 4425) SIG_NAME M_B_CPU1_SB_DQS_DN<5>
J 0
(-6015 4435);
DISPLAY 0.659574 (-6015 4435);
PAINT MONO (-6015 4435);
DISPLAY INVISIBLE (-6015 4435);
FORCEPROP 1 LASTPIN (-6025 4425) BN 5
J 2
(-6013 4433);
DISPLAY 0.489362 (-6013 4433);
PAINT GREEN (-6013 4433);
FORCEPROP 2 LAST CDS_LIB mstr_standard
J 2
(-6075 4425);
DISPLAY 0.723404 (-6075 4425);
PAINT MONO (-6075 4425);
DISPLAY INVISIBLE (-6075 4425);
FORCEPROP 1 LAST BODY_TYPE PLUMBING
J 2
(-6075 4475);
DISPLAY 0.872340 (-6075 4475);
PAINT GREEN (-6075 4475);
DISPLAY INVISIBLE (-6075 4475);
FORCEPROP 1 LAST HDL_TAP TRUE
J 2
(-6400 4300);
DISPLAY 0.872340 (-6400 4300);
DISPLAY INVISIBLE (-6400 4300);
FORCEPROP 1 LAST PATH I277
J 2
(-6073 4425);
DISPLAY 0.872340 (-6073 4425);
PAINT GREEN (-6073 4425);
DISPLAY INVISIBLE (-6073 4425);
FORCEADD TAP..1
R 2
(-6075 4525);
FORCEPROP 3 LASTPIN (-6025 4525) SIG_NAME M_B_CPU1_SB_DQS_DN<4>
J 0
(-6015 4535);
DISPLAY 0.659574 (-6015 4535);
PAINT MONO (-6015 4535);
DISPLAY INVISIBLE (-6015 4535);
FORCEPROP 1 LASTPIN (-6025 4525) BN 4
J 2
(-6013 4533);
DISPLAY 0.489362 (-6013 4533);
PAINT GREEN (-6013 4533);
FORCEPROP 2 LAST CDS_LIB mstr_standard
J 2
(-6075 4525);
DISPLAY 0.723404 (-6075 4525);
PAINT MONO (-6075 4525);
DISPLAY INVISIBLE (-6075 4525);
FORCEPROP 1 LAST BODY_TYPE PLUMBING
J 2
(-6075 4575);
DISPLAY 0.872340 (-6075 4575);
PAINT GREEN (-6075 4575);
DISPLAY INVISIBLE (-6075 4575);
FORCEPROP 1 LAST HDL_TAP TRUE
J 2
(-6400 4400);
DISPLAY 0.872340 (-6400 4400);
DISPLAY INVISIBLE (-6400 4400);
FORCEPROP 1 LAST PATH I278
J 2
(-6073 4525);
DISPLAY 0.872340 (-6073 4525);
PAINT GREEN (-6073 4525);
DISPLAY INVISIBLE (-6073 4525);
FORCEADD TAP..1
R 2
(-6075 4325);
FORCEPROP 3 LASTPIN (-6025 4325) SIG_NAME M_B_CPU1_SB_DQS_DN<6>
J 0
(-6015 4335);
DISPLAY 0.659574 (-6015 4335);
PAINT MONO (-6015 4335);
DISPLAY INVISIBLE (-6015 4335);
FORCEPROP 1 LASTPIN (-6025 4325) BN 6
J 2
(-6013 4333);
DISPLAY 0.489362 (-6013 4333);
PAINT GREEN (-6013 4333);
FORCEPROP 2 LAST CDS_LIB mstr_standard
J 2
(-6075 4325);
DISPLAY 0.723404 (-6075 4325);
PAINT MONO (-6075 4325);
DISPLAY INVISIBLE (-6075 4325);
FORCEPROP 1 LAST BODY_TYPE PLUMBING
J 2
(-6075 4375);
DISPLAY 0.872340 (-6075 4375);
PAINT GREEN (-6075 4375);
DISPLAY INVISIBLE (-6075 4375);
FORCEPROP 1 LAST HDL_TAP TRUE
J 2
(-6400 4200);
DISPLAY 0.872340 (-6400 4200);
DISPLAY INVISIBLE (-6400 4200);
FORCEPROP 1 LAST PATH I279
J 2
(-6073 4325);
DISPLAY 0.872340 (-6073 4325);
PAINT GREEN (-6073 4325);
DISPLAY INVISIBLE (-6073 4325);
FORCEADD TAP..1
R 2
(-6075 4225);
FORCEPROP 3 LASTPIN (-6025 4225) SIG_NAME M_B_CPU1_SB_DQS_DN<7>
J 0
(-6015 4235);
DISPLAY 0.659574 (-6015 4235);
PAINT MONO (-6015 4235);
DISPLAY INVISIBLE (-6015 4235);
FORCEPROP 1 LASTPIN (-6025 4225) BN 7
J 2
(-6013 4233);
DISPLAY 0.489362 (-6013 4233);
PAINT GREEN (-6013 4233);
FORCEPROP 2 LAST CDS_LIB mstr_standard
J 2
(-6075 4225);
DISPLAY 0.723404 (-6075 4225);
PAINT MONO (-6075 4225);
DISPLAY INVISIBLE (-6075 4225);
FORCEPROP 1 LAST BODY_TYPE PLUMBING
J 2
(-6075 4275);
DISPLAY 0.872340 (-6075 4275);
PAINT GREEN (-6075 4275);
DISPLAY INVISIBLE (-6075 4275);
FORCEPROP 1 LAST HDL_TAP TRUE
J 2
(-6400 4100);
DISPLAY 0.872340 (-6400 4100);
DISPLAY INVISIBLE (-6400 4100);
FORCEPROP 1 LAST PATH I280
J 2
(-6073 4225);
DISPLAY 0.872340 (-6073 4225);
PAINT GREEN (-6073 4225);
DISPLAY INVISIBLE (-6073 4225);
FORCEADD TAP..1
R 2
(-6075 4125);
FORCEPROP 3 LASTPIN (-6025 4125) SIG_NAME M_B_CPU1_SB_DQS_DN<8>
J 0
(-6015 4135);
DISPLAY 0.659574 (-6015 4135);
PAINT MONO (-6015 4135);
DISPLAY INVISIBLE (-6015 4135);
FORCEPROP 1 LASTPIN (-6025 4125) BN 8
J 2
(-6013 4133);
DISPLAY 0.489362 (-6013 4133);
PAINT GREEN (-6013 4133);
FORCEPROP 2 LAST CDS_LIB mstr_standard
J 2
(-6075 4125);
DISPLAY 0.723404 (-6075 4125);
PAINT MONO (-6075 4125);
DISPLAY INVISIBLE (-6075 4125);
FORCEPROP 1 LAST BODY_TYPE PLUMBING
J 2
(-6075 4175);
DISPLAY 0.872340 (-6075 4175);
PAINT GREEN (-6075 4175);
DISPLAY INVISIBLE (-6075 4175);
FORCEPROP 1 LAST HDL_TAP TRUE
J 2
(-6400 4000);
DISPLAY 0.872340 (-6400 4000);
DISPLAY INVISIBLE (-6400 4000);
FORCEPROP 1 LAST PATH I281
J 2
(-6073 4125);
DISPLAY 0.872340 (-6073 4125);
PAINT GREEN (-6073 4125);
DISPLAY INVISIBLE (-6073 4125);
FORCEADD OFFPAGE..3
R 2
(-6775 6050);
FORCEPROP 2 LAST $XR0 99 
J 0
(-7054 6050);
DISPLAY 0.638298 (-7054 6050);
PAINT MONO (-7054 6050);
FORCEPROP 2 LAST CDS_LIB standard
J 0
(-6775 6050);
DISPLAY INVISIBLE (-6775 6050);
FORCEPROP 1 LAST OFFPAGE TRUE
J 2
(-7100 5925);
DISPLAY 0.872340 (-7100 5925);
PAINT GREEN (-7100 5925);
DISPLAY INVISIBLE (-7100 5925);
FORCEPROP 1 LAST COMMENT_BODY TRUE
J 2
(-6725 5950);
DISPLAY 0.872340 (-6725 5950);
PAINT GREEN (-6725 5950);
DISPLAY INVISIBLE (-6725 5950);
FORCEPROP 2 LAST PATH I282
J 0
(-7075 6100);
DISPLAY 1.021277 (-7075 6100);
DISPLAY INVISIBLE (-7075 6100);
FORCEADD OFFPAGE..3
R 2
(-6775 6000);
FORCEPROP 2 LAST $XR0 99 
J 0
(-7054 6000);
DISPLAY 0.638298 (-7054 6000);
PAINT MONO (-7054 6000);
FORCEPROP 2 LAST CDS_LIB standard
J 0
(-6775 6000);
DISPLAY INVISIBLE (-6775 6000);
FORCEPROP 1 LAST OFFPAGE TRUE
J 2
(-7100 5875);
DISPLAY 0.872340 (-7100 5875);
PAINT GREEN (-7100 5875);
DISPLAY INVISIBLE (-7100 5875);
FORCEPROP 1 LAST COMMENT_BODY TRUE
J 2
(-6725 5900);
DISPLAY 0.872340 (-6725 5900);
PAINT GREEN (-6725 5900);
DISPLAY INVISIBLE (-6725 5900);
FORCEPROP 2 LAST PATH I283
J 0
(-7075 6050);
DISPLAY 1.021277 (-7075 6050);
DISPLAY INVISIBLE (-7075 6050);
FORCEADD OFFPAGE..3
R 2
(-6775 4950);
FORCEPROP 2 LAST $XR0 99 
J 0
(-7054 4950);
DISPLAY 0.638298 (-7054 4950);
PAINT MONO (-7054 4950);
FORCEPROP 2 LAST CDS_LIB standard
J 0
(-6775 4950);
DISPLAY INVISIBLE (-6775 4950);
FORCEPROP 1 LAST OFFPAGE TRUE
J 2
(-7100 4825);
DISPLAY 0.872340 (-7100 4825);
PAINT GREEN (-7100 4825);
DISPLAY INVISIBLE (-7100 4825);
FORCEPROP 1 LAST COMMENT_BODY TRUE
J 2
(-6725 4850);
DISPLAY 0.872340 (-6725 4850);
PAINT GREEN (-6725 4850);
DISPLAY INVISIBLE (-6725 4850);
FORCEPROP 2 LAST PATH I284
J 0
(-7075 5000);
DISPLAY 1.021277 (-7075 5000);
DISPLAY INVISIBLE (-7075 5000);
FORCEADD OFFPAGE..3
R 2
(-6775 5000);
FORCEPROP 2 LAST $XR0 99 
J 0
(-7054 5000);
DISPLAY 0.638298 (-7054 5000);
PAINT MONO (-7054 5000);
FORCEPROP 2 LAST CDS_LIB standard
J 0
(-6775 5000);
DISPLAY INVISIBLE (-6775 5000);
FORCEPROP 1 LAST OFFPAGE TRUE
J 2
(-7100 4875);
DISPLAY 0.872340 (-7100 4875);
PAINT GREEN (-7100 4875);
DISPLAY INVISIBLE (-7100 4875);
FORCEPROP 1 LAST COMMENT_BODY TRUE
J 2
(-6725 4900);
DISPLAY 0.872340 (-6725 4900);
PAINT GREEN (-6725 4900);
DISPLAY INVISIBLE (-6725 4900);
FORCEPROP 2 LAST PATH I285
J 0
(-7075 5050);
DISPLAY 1.021277 (-7075 5050);
DISPLAY INVISIBLE (-7075 5050);
FORCEADD TAP..1
R 2
(-5875 4075);
FORCEPROP 3 LASTPIN (-5825 4075) SIG_NAME M_B_CPU1_SB_DQS_DP<9>
J 0
(-5815 4085);
DISPLAY 0.659574 (-5815 4085);
PAINT MONO (-5815 4085);
DISPLAY INVISIBLE (-5815 4085);
FORCEPROP 1 LASTPIN (-5825 4075) BN 9
J 2
(-5813 4083);
DISPLAY 0.489362 (-5813 4083);
PAINT GREEN (-5813 4083);
FORCEPROP 2 LAST CDS_LIB mstr_standard
J 2
(-5875 4075);
DISPLAY 0.723404 (-5875 4075);
PAINT MONO (-5875 4075);
DISPLAY INVISIBLE (-5875 4075);
FORCEPROP 1 LAST BODY_TYPE PLUMBING
J 2
(-5875 4125);
DISPLAY 0.872340 (-5875 4125);
PAINT GREEN (-5875 4125);
DISPLAY INVISIBLE (-5875 4125);
FORCEPROP 1 LAST HDL_TAP TRUE
J 2
(-6200 3950);
DISPLAY 0.872340 (-6200 3950);
DISPLAY INVISIBLE (-6200 3950);
FORCEPROP 1 LAST PATH I286
J 2
(-5873 4075);
DISPLAY 0.872340 (-5873 4075);
PAINT GREEN (-5873 4075);
DISPLAY INVISIBLE (-5873 4075);
FORCEADD TAP..1
R 2
(-6075 3875);
FORCEPROP 3 LASTPIN (-6025 3875) SIG_NAME M_B_CPU1_SA_CA<0>
J 0
(-6015 3885);
DISPLAY 0.659574 (-6015 3885);
PAINT MONO (-6015 3885);
DISPLAY INVISIBLE (-6015 3885);
FORCEPROP 1 LASTPIN (-6025 3875) BN 0
J 2
(-6013 3883);
DISPLAY 0.489362 (-6013 3883);
PAINT GREEN (-6013 3883);
FORCEPROP 2 LAST CDS_LIB mstr_standard
J 0
(-6075 3875);
DISPLAY 0.723404 (-6075 3875);
PAINT MONO (-6075 3875);
DISPLAY INVISIBLE (-6075 3875);
FORCEPROP 1 LAST BODY_TYPE PLUMBING
J 2
(-6075 3925);
DISPLAY 0.872340 (-6075 3925);
PAINT GREEN (-6075 3925);
DISPLAY INVISIBLE (-6075 3925);
FORCEPROP 1 LAST HDL_TAP TRUE
J 2
(-6400 3750);
DISPLAY 0.872340 (-6400 3750);
DISPLAY INVISIBLE (-6400 3750);
FORCEPROP 1 LAST PATH I287
J 2
(-6073 3875);
DISPLAY 0.872340 (-6073 3875);
PAINT GREEN (-6073 3875);
DISPLAY INVISIBLE (-6073 3875);
FORCEADD TAP..1
R 2
(-6075 4025);
FORCEPROP 3 LASTPIN (-6025 4025) SIG_NAME M_B_CPU1_SB_DQS_DN<9>
J 0
(-6015 4035);
DISPLAY 0.659574 (-6015 4035);
PAINT MONO (-6015 4035);
DISPLAY INVISIBLE (-6015 4035);
FORCEPROP 1 LASTPIN (-6025 4025) BN 9
J 2
(-6013 4033);
DISPLAY 0.489362 (-6013 4033);
PAINT GREEN (-6013 4033);
FORCEPROP 2 LAST CDS_LIB mstr_standard
J 2
(-6075 4025);
DISPLAY 0.723404 (-6075 4025);
PAINT MONO (-6075 4025);
DISPLAY INVISIBLE (-6075 4025);
FORCEPROP 1 LAST BODY_TYPE PLUMBING
J 2
(-6075 4075);
DISPLAY 0.872340 (-6075 4075);
PAINT GREEN (-6075 4075);
DISPLAY INVISIBLE (-6075 4075);
FORCEPROP 1 LAST HDL_TAP TRUE
J 2
(-6400 3900);
DISPLAY 0.872340 (-6400 3900);
DISPLAY INVISIBLE (-6400 3900);
FORCEPROP 1 LAST PATH I288
J 2
(-6073 4025);
DISPLAY 0.872340 (-6073 4025);
PAINT GREEN (-6073 4025);
DISPLAY INVISIBLE (-6073 4025);
FORCEADD TAP..1
R 2
(-6075 3825);
FORCEPROP 3 LASTPIN (-6025 3825) SIG_NAME M_B_CPU1_SA_CA<1>
J 0
(-6015 3835);
DISPLAY 0.659574 (-6015 3835);
PAINT MONO (-6015 3835);
DISPLAY INVISIBLE (-6015 3835);
FORCEPROP 1 LASTPIN (-6025 3825) BN 1
J 2
(-6013 3833);
DISPLAY 0.489362 (-6013 3833);
PAINT GREEN (-6013 3833);
FORCEPROP 2 LAST CDS_LIB mstr_standard
J 0
(-6075 3825);
DISPLAY 0.723404 (-6075 3825);
PAINT MONO (-6075 3825);
DISPLAY INVISIBLE (-6075 3825);
FORCEPROP 1 LAST BODY_TYPE PLUMBING
J 2
(-6075 3875);
DISPLAY 0.872340 (-6075 3875);
PAINT GREEN (-6075 3875);
DISPLAY INVISIBLE (-6075 3875);
FORCEPROP 1 LAST HDL_TAP TRUE
J 2
(-6400 3700);
DISPLAY 0.872340 (-6400 3700);
DISPLAY INVISIBLE (-6400 3700);
FORCEPROP 1 LAST PATH I289
J 2
(-6073 3825);
DISPLAY 0.872340 (-6073 3825);
PAINT GREEN (-6073 3825);
DISPLAY INVISIBLE (-6073 3825);
FORCEADD TAP..1
R 2
(-6075 3725);
FORCEPROP 3 LASTPIN (-6025 3725) SIG_NAME M_B_CPU1_SA_CA<3>
J 0
(-6015 3735);
DISPLAY 0.659574 (-6015 3735);
PAINT MONO (-6015 3735);
DISPLAY INVISIBLE (-6015 3735);
FORCEPROP 1 LASTPIN (-6025 3725) BN 3
J 2
(-6013 3733);
DISPLAY 0.489362 (-6013 3733);
PAINT GREEN (-6013 3733);
FORCEPROP 2 LAST CDS_LIB mstr_standard
J 0
(-6075 3725);
DISPLAY 0.723404 (-6075 3725);
PAINT MONO (-6075 3725);
DISPLAY INVISIBLE (-6075 3725);
FORCEPROP 1 LAST BODY_TYPE PLUMBING
J 2
(-6075 3775);
DISPLAY 0.872340 (-6075 3775);
PAINT GREEN (-6075 3775);
DISPLAY INVISIBLE (-6075 3775);
FORCEPROP 1 LAST HDL_TAP TRUE
J 2
(-6400 3600);
DISPLAY 0.872340 (-6400 3600);
DISPLAY INVISIBLE (-6400 3600);
FORCEPROP 1 LAST PATH I290
J 2
(-6073 3725);
DISPLAY 0.872340 (-6073 3725);
PAINT GREEN (-6073 3725);
DISPLAY INVISIBLE (-6073 3725);
FORCEADD TAP..1
R 2
(-6075 3775);
FORCEPROP 3 LASTPIN (-6025 3775) SIG_NAME M_B_CPU1_SA_CA<2>
J 0
(-6015 3785);
DISPLAY 0.659574 (-6015 3785);
PAINT MONO (-6015 3785);
DISPLAY INVISIBLE (-6015 3785);
FORCEPROP 1 LASTPIN (-6025 3775) BN 2
J 2
(-6013 3783);
DISPLAY 0.489362 (-6013 3783);
PAINT GREEN (-6013 3783);
FORCEPROP 2 LAST CDS_LIB mstr_standard
J 0
(-6075 3775);
DISPLAY 0.723404 (-6075 3775);
PAINT MONO (-6075 3775);
DISPLAY INVISIBLE (-6075 3775);
FORCEPROP 1 LAST BODY_TYPE PLUMBING
J 2
(-6075 3825);
DISPLAY 0.872340 (-6075 3825);
PAINT GREEN (-6075 3825);
DISPLAY INVISIBLE (-6075 3825);
FORCEPROP 1 LAST HDL_TAP TRUE
J 2
(-6400 3650);
DISPLAY 0.872340 (-6400 3650);
DISPLAY INVISIBLE (-6400 3650);
FORCEPROP 1 LAST PATH I291
J 2
(-6073 3775);
DISPLAY 0.872340 (-6073 3775);
PAINT GREEN (-6073 3775);
DISPLAY INVISIBLE (-6073 3775);
FORCEADD TAP..1
R 2
(-6075 3675);
FORCEPROP 3 LASTPIN (-6025 3675) SIG_NAME M_B_CPU1_SA_CA<4>
J 0
(-6015 3685);
DISPLAY 0.659574 (-6015 3685);
PAINT MONO (-6015 3685);
DISPLAY INVISIBLE (-6015 3685);
FORCEPROP 1 LASTPIN (-6025 3675) BN 4
J 2
(-6013 3683);
DISPLAY 0.489362 (-6013 3683);
PAINT GREEN (-6013 3683);
FORCEPROP 2 LAST CDS_LIB mstr_standard
J 0
(-6075 3675);
DISPLAY 0.723404 (-6075 3675);
PAINT MONO (-6075 3675);
DISPLAY INVISIBLE (-6075 3675);
FORCEPROP 1 LAST BODY_TYPE PLUMBING
J 2
(-6075 3725);
DISPLAY 0.872340 (-6075 3725);
PAINT GREEN (-6075 3725);
DISPLAY INVISIBLE (-6075 3725);
FORCEPROP 1 LAST HDL_TAP TRUE
J 2
(-6400 3550);
DISPLAY 0.872340 (-6400 3550);
DISPLAY INVISIBLE (-6400 3550);
FORCEPROP 1 LAST PATH I292
J 2
(-6073 3675);
DISPLAY 0.872340 (-6073 3675);
PAINT GREEN (-6073 3675);
DISPLAY INVISIBLE (-6073 3675);
FORCEADD TAP..1
R 2
(-6075 3625);
FORCEPROP 3 LASTPIN (-6025 3625) SIG_NAME M_B_CPU1_SA_CA<5>
J 0
(-6015 3635);
DISPLAY 0.659574 (-6015 3635);
PAINT MONO (-6015 3635);
DISPLAY INVISIBLE (-6015 3635);
FORCEPROP 1 LASTPIN (-6025 3625) BN 5
J 2
(-6013 3633);
DISPLAY 0.489362 (-6013 3633);
PAINT GREEN (-6013 3633);
FORCEPROP 2 LAST CDS_LIB mstr_standard
J 0
(-6075 3625);
DISPLAY 0.723404 (-6075 3625);
PAINT MONO (-6075 3625);
DISPLAY INVISIBLE (-6075 3625);
FORCEPROP 1 LAST BODY_TYPE PLUMBING
J 2
(-6075 3675);
DISPLAY 0.872340 (-6075 3675);
PAINT GREEN (-6075 3675);
DISPLAY INVISIBLE (-6075 3675);
FORCEPROP 1 LAST HDL_TAP TRUE
J 2
(-6400 3500);
DISPLAY 0.872340 (-6400 3500);
DISPLAY INVISIBLE (-6400 3500);
FORCEPROP 1 LAST PATH I293
J 2
(-6073 3625);
DISPLAY 0.872340 (-6073 3625);
PAINT GREEN (-6073 3625);
DISPLAY INVISIBLE (-6073 3625);
FORCEADD TAP..1
R 2
(-6075 3575);
FORCEPROP 3 LASTPIN (-6025 3575) SIG_NAME M_B_CPU1_SA_CA<6>
J 0
(-6015 3585);
DISPLAY 0.659574 (-6015 3585);
PAINT MONO (-6015 3585);
DISPLAY INVISIBLE (-6015 3585);
FORCEPROP 1 LASTPIN (-6025 3575) BN 6
J 2
(-6013 3583);
DISPLAY 0.489362 (-6013 3583);
PAINT GREEN (-6013 3583);
FORCEPROP 2 LAST CDS_LIB mstr_standard
J 0
(-6075 3575);
DISPLAY 0.723404 (-6075 3575);
PAINT MONO (-6075 3575);
DISPLAY INVISIBLE (-6075 3575);
FORCEPROP 1 LAST BODY_TYPE PLUMBING
J 2
(-6075 3625);
DISPLAY 0.872340 (-6075 3625);
PAINT GREEN (-6075 3625);
DISPLAY INVISIBLE (-6075 3625);
FORCEPROP 1 LAST HDL_TAP TRUE
J 2
(-6400 3450);
DISPLAY 0.872340 (-6400 3450);
DISPLAY INVISIBLE (-6400 3450);
FORCEPROP 1 LAST PATH I294
J 2
(-6073 3575);
DISPLAY 0.872340 (-6073 3575);
PAINT GREEN (-6073 3575);
DISPLAY INVISIBLE (-6073 3575);
FORCEADD TAP..1
R 2
(-6075 3425);
FORCEPROP 3 LASTPIN (-6025 3425) SIG_NAME M_B_CPU1_SB_CA<1>
J 0
(-6015 3435);
DISPLAY 0.659574 (-6015 3435);
PAINT MONO (-6015 3435);
DISPLAY INVISIBLE (-6015 3435);
FORCEPROP 1 LASTPIN (-6025 3425) BN 1
J 2
(-6013 3433);
DISPLAY 0.489362 (-6013 3433);
PAINT GREEN (-6013 3433);
FORCEPROP 2 LAST CDS_LIB mstr_standard
J 0
(-6075 3425);
DISPLAY 0.723404 (-6075 3425);
PAINT MONO (-6075 3425);
DISPLAY INVISIBLE (-6075 3425);
FORCEPROP 1 LAST BODY_TYPE PLUMBING
J 2
(-6075 3475);
DISPLAY 0.872340 (-6075 3475);
PAINT GREEN (-6075 3475);
DISPLAY INVISIBLE (-6075 3475);
FORCEPROP 1 LAST HDL_TAP TRUE
J 2
(-6400 3300);
DISPLAY 0.872340 (-6400 3300);
DISPLAY INVISIBLE (-6400 3300);
FORCEPROP 1 LAST PATH I295
J 2
(-6073 3425);
DISPLAY 0.872340 (-6073 3425);
PAINT GREEN (-6073 3425);
DISPLAY INVISIBLE (-6073 3425);
FORCEADD TAP..1
R 2
(-6075 3475);
FORCEPROP 3 LASTPIN (-6025 3475) SIG_NAME M_B_CPU1_SB_CA<0>
J 0
(-6015 3485);
DISPLAY 0.659574 (-6015 3485);
PAINT MONO (-6015 3485);
DISPLAY INVISIBLE (-6015 3485);
FORCEPROP 1 LASTPIN (-6025 3475) BN 0
J 2
(-6013 3483);
DISPLAY 0.489362 (-6013 3483);
PAINT GREEN (-6013 3483);
FORCEPROP 2 LAST CDS_LIB mstr_standard
J 0
(-6075 3475);
DISPLAY 0.723404 (-6075 3475);
PAINT MONO (-6075 3475);
DISPLAY INVISIBLE (-6075 3475);
FORCEPROP 1 LAST BODY_TYPE PLUMBING
J 2
(-6075 3525);
DISPLAY 0.872340 (-6075 3525);
PAINT GREEN (-6075 3525);
DISPLAY INVISIBLE (-6075 3525);
FORCEPROP 1 LAST HDL_TAP TRUE
J 2
(-6400 3350);
DISPLAY 0.872340 (-6400 3350);
DISPLAY INVISIBLE (-6400 3350);
FORCEPROP 1 LAST PATH I296
J 2
(-6073 3475);
DISPLAY 0.872340 (-6073 3475);
PAINT GREEN (-6073 3475);
DISPLAY INVISIBLE (-6073 3475);
FORCEADD TAP..1
R 2
(-6075 3375);
FORCEPROP 3 LASTPIN (-6025 3375) SIG_NAME M_B_CPU1_SB_CA<2>
J 0
(-6015 3385);
DISPLAY 0.659574 (-6015 3385);
PAINT MONO (-6015 3385);
DISPLAY INVISIBLE (-6015 3385);
FORCEPROP 1 LASTPIN (-6025 3375) BN 2
J 2
(-6013 3383);
DISPLAY 0.489362 (-6013 3383);
PAINT GREEN (-6013 3383);
FORCEPROP 2 LAST CDS_LIB mstr_standard
J 0
(-6075 3375);
DISPLAY 0.723404 (-6075 3375);
PAINT MONO (-6075 3375);
DISPLAY INVISIBLE (-6075 3375);
FORCEPROP 1 LAST BODY_TYPE PLUMBING
J 2
(-6075 3425);
DISPLAY 0.872340 (-6075 3425);
PAINT GREEN (-6075 3425);
DISPLAY INVISIBLE (-6075 3425);
FORCEPROP 1 LAST HDL_TAP TRUE
J 2
(-6400 3250);
DISPLAY 0.872340 (-6400 3250);
DISPLAY INVISIBLE (-6400 3250);
FORCEPROP 1 LAST PATH I297
J 2
(-6073 3375);
DISPLAY 0.872340 (-6073 3375);
PAINT GREEN (-6073 3375);
DISPLAY INVISIBLE (-6073 3375);
FORCEADD TAP..1
R 2
(-6075 3325);
FORCEPROP 3 LASTPIN (-6025 3325) SIG_NAME M_B_CPU1_SB_CA<3>
J 0
(-6015 3335);
DISPLAY 0.659574 (-6015 3335);
PAINT MONO (-6015 3335);
DISPLAY INVISIBLE (-6015 3335);
FORCEPROP 1 LASTPIN (-6025 3325) BN 3
J 2
(-6013 3333);
DISPLAY 0.489362 (-6013 3333);
PAINT GREEN (-6013 3333);
FORCEPROP 2 LAST CDS_LIB mstr_standard
J 0
(-6075 3325);
DISPLAY 0.723404 (-6075 3325);
PAINT MONO (-6075 3325);
DISPLAY INVISIBLE (-6075 3325);
FORCEPROP 1 LAST BODY_TYPE PLUMBING
J 2
(-6075 3375);
DISPLAY 0.872340 (-6075 3375);
PAINT GREEN (-6075 3375);
DISPLAY INVISIBLE (-6075 3375);
FORCEPROP 1 LAST HDL_TAP TRUE
J 2
(-6400 3200);
DISPLAY 0.872340 (-6400 3200);
DISPLAY INVISIBLE (-6400 3200);
FORCEPROP 1 LAST PATH I298
J 2
(-6073 3325);
DISPLAY 0.872340 (-6073 3325);
PAINT GREEN (-6073 3325);
DISPLAY INVISIBLE (-6073 3325);
FORCEADD TAP..1
R 2
(-6075 3175);
FORCEPROP 3 LASTPIN (-6025 3175) SIG_NAME M_B_CPU1_SB_CA<6>
J 0
(-6015 3185);
DISPLAY 0.659574 (-6015 3185);
PAINT MONO (-6015 3185);
DISPLAY INVISIBLE (-6015 3185);
FORCEPROP 1 LASTPIN (-6025 3175) BN 6
J 2
(-6013 3183);
DISPLAY 0.489362 (-6013 3183);
PAINT GREEN (-6013 3183);
FORCEPROP 2 LAST CDS_LIB mstr_standard
J 0
(-6075 3175);
DISPLAY 0.723404 (-6075 3175);
PAINT MONO (-6075 3175);
DISPLAY INVISIBLE (-6075 3175);
FORCEPROP 1 LAST BODY_TYPE PLUMBING
J 2
(-6075 3225);
DISPLAY 0.872340 (-6075 3225);
PAINT GREEN (-6075 3225);
DISPLAY INVISIBLE (-6075 3225);
FORCEPROP 1 LAST HDL_TAP TRUE
J 2
(-6400 3050);
DISPLAY 0.872340 (-6400 3050);
DISPLAY INVISIBLE (-6400 3050);
FORCEPROP 1 LAST PATH I299
J 2
(-6073 3175);
DISPLAY 0.872340 (-6073 3175);
PAINT GREEN (-6073 3175);
DISPLAY INVISIBLE (-6073 3175);
FORCEADD TAP..1
R 2
(-6075 3275);
FORCEPROP 3 LASTPIN (-6025 3275) SIG_NAME M_B_CPU1_SB_CA<4>
J 0
(-6015 3285);
DISPLAY 0.659574 (-6015 3285);
PAINT MONO (-6015 3285);
DISPLAY INVISIBLE (-6015 3285);
FORCEPROP 1 LASTPIN (-6025 3275) BN 4
J 2
(-6013 3283);
DISPLAY 0.489362 (-6013 3283);
PAINT GREEN (-6013 3283);
FORCEPROP 2 LAST CDS_LIB mstr_standard
J 0
(-6075 3275);
DISPLAY 0.723404 (-6075 3275);
PAINT MONO (-6075 3275);
DISPLAY INVISIBLE (-6075 3275);
FORCEPROP 1 LAST BODY_TYPE PLUMBING
J 2
(-6075 3325);
DISPLAY 0.872340 (-6075 3325);
PAINT GREEN (-6075 3325);
DISPLAY INVISIBLE (-6075 3325);
FORCEPROP 1 LAST HDL_TAP TRUE
J 2
(-6400 3150);
DISPLAY 0.872340 (-6400 3150);
DISPLAY INVISIBLE (-6400 3150);
FORCEPROP 1 LAST PATH I300
J 2
(-6073 3275);
DISPLAY 0.872340 (-6073 3275);
PAINT GREEN (-6073 3275);
DISPLAY INVISIBLE (-6073 3275);
FORCEADD TAP..1
R 2
(-6075 3225);
FORCEPROP 3 LASTPIN (-6025 3225) SIG_NAME M_B_CPU1_SB_CA<5>
J 0
(-6015 3235);
DISPLAY 0.659574 (-6015 3235);
PAINT MONO (-6015 3235);
DISPLAY INVISIBLE (-6015 3235);
FORCEPROP 1 LASTPIN (-6025 3225) BN 5
J 2
(-6013 3233);
DISPLAY 0.489362 (-6013 3233);
PAINT GREEN (-6013 3233);
FORCEPROP 2 LAST CDS_LIB mstr_standard
J 0
(-6075 3225);
DISPLAY 0.723404 (-6075 3225);
PAINT MONO (-6075 3225);
DISPLAY INVISIBLE (-6075 3225);
FORCEPROP 1 LAST BODY_TYPE PLUMBING
J 2
(-6075 3275);
DISPLAY 0.872340 (-6075 3275);
PAINT GREEN (-6075 3275);
DISPLAY INVISIBLE (-6075 3275);
FORCEPROP 1 LAST HDL_TAP TRUE
J 2
(-6400 3100);
DISPLAY 0.872340 (-6400 3100);
DISPLAY INVISIBLE (-6400 3100);
FORCEPROP 1 LAST PATH I301
J 2
(-6073 3225);
DISPLAY 0.872340 (-6073 3225);
PAINT GREEN (-6073 3225);
DISPLAY INVISIBLE (-6073 3225);
FORCEADD OFFPAGE..2
R 2
(-6675 3900);
FORCEPROP 2 LAST $XR0 99 
J 0
(-6899 3900);
DISPLAY 0.638298 (-6899 3900);
PAINT MONO (-6899 3900);
FORCEPROP 2 LAST CDS_LIB standard
J 0
(-6675 3900);
DISPLAY INVISIBLE (-6675 3900);
FORCEPROP 1 LAST OFFPAGE TRUE
J 2
(-7000 3775);
DISPLAY 0.872340 (-7000 3775);
PAINT GREEN (-7000 3775);
DISPLAY INVISIBLE (-7000 3775);
FORCEPROP 1 LAST COMMENT_BODY TRUE
J 2
(-6630 3805);
DISPLAY 0.872340 (-6630 3805);
PAINT GREEN (-6630 3805);
DISPLAY INVISIBLE (-6630 3805);
FORCEPROP 2 LAST PATH I302
J 0
(-6925 3950);
DISPLAY 1.021277 (-6925 3950);
DISPLAY INVISIBLE (-6925 3950);
FORCEADD OFFPAGE..2
R 2
(-6675 3500);
FORCEPROP 2 LAST $XR0 99 
J 0
(-6899 3500);
DISPLAY 0.638298 (-6899 3500);
PAINT MONO (-6899 3500);
FORCEPROP 2 LAST CDS_LIB standard
J 0
(-6675 3500);
DISPLAY INVISIBLE (-6675 3500);
FORCEPROP 1 LAST OFFPAGE TRUE
J 2
(-7000 3375);
DISPLAY 0.872340 (-7000 3375);
PAINT GREEN (-7000 3375);
DISPLAY INVISIBLE (-7000 3375);
FORCEPROP 1 LAST COMMENT_BODY TRUE
J 2
(-6630 3405);
DISPLAY 0.872340 (-6630 3405);
PAINT GREEN (-6630 3405);
DISPLAY INVISIBLE (-6630 3405);
FORCEPROP 2 LAST PATH I303
J 0
(-6925 3550);
DISPLAY 1.021277 (-6925 3550);
DISPLAY INVISIBLE (-6925 3550);
FORCEADD OFFPAGE..2
R 2
(-6675 3025);
FORCEPROP 2 LAST $XR0 99 
J 0
(-6899 3025);
DISPLAY 0.638298 (-6899 3025);
PAINT MONO (-6899 3025);
FORCEPROP 2 LAST CDS_LIB standard
J 0
(-6675 3025);
DISPLAY INVISIBLE (-6675 3025);
FORCEPROP 1 LAST OFFPAGE TRUE
J 2
(-7000 2900);
DISPLAY 0.872340 (-7000 2900);
PAINT GREEN (-7000 2900);
DISPLAY INVISIBLE (-7000 2900);
FORCEPROP 1 LAST COMMENT_BODY TRUE
J 2
(-6630 2930);
DISPLAY 0.872340 (-6630 2930);
PAINT GREEN (-6630 2930);
DISPLAY INVISIBLE (-6630 2930);
FORCEPROP 2 LAST PATH I304
J 0
(-6925 3075);
DISPLAY 1.021277 (-6925 3075);
DISPLAY INVISIBLE (-6925 3075);
FORCEADD OFFPAGE..2
R 2
(-6675 2975);
FORCEPROP 2 LAST $XR0 99 
J 0
(-6899 2975);
DISPLAY 0.638298 (-6899 2975);
PAINT MONO (-6899 2975);
FORCEPROP 2 LAST CDS_LIB standard
J 0
(-6675 2975);
DISPLAY INVISIBLE (-6675 2975);
FORCEPROP 1 LAST OFFPAGE TRUE
J 2
(-7000 2850);
DISPLAY 0.872340 (-7000 2850);
PAINT GREEN (-7000 2850);
DISPLAY INVISIBLE (-7000 2850);
FORCEPROP 1 LAST COMMENT_BODY TRUE
J 2
(-6630 2880);
DISPLAY 0.872340 (-6630 2880);
PAINT GREEN (-6630 2880);
DISPLAY INVISIBLE (-6630 2880);
FORCEPROP 2 LAST PATH I305
J 0
(-6925 3025);
DISPLAY 1.021277 (-6925 3025);
DISPLAY INVISIBLE (-6925 3025);
FORCEADD OFFPAGE..2
R 2
(-6675 2875);
FORCEPROP 2 LAST $XR0 99 
J 0
(-6899 2875);
DISPLAY 0.638298 (-6899 2875);
PAINT MONO (-6899 2875);
FORCEPROP 2 LAST CDS_LIB standard
J 0
(-6675 2875);
DISPLAY INVISIBLE (-6675 2875);
FORCEPROP 1 LAST OFFPAGE TRUE
J 2
(-7000 2750);
DISPLAY 0.872340 (-7000 2750);
PAINT GREEN (-7000 2750);
DISPLAY INVISIBLE (-7000 2750);
FORCEPROP 1 LAST COMMENT_BODY TRUE
J 2
(-6630 2780);
DISPLAY 0.872340 (-6630 2780);
PAINT GREEN (-6630 2780);
DISPLAY INVISIBLE (-6630 2780);
FORCEPROP 2 LAST PATH I306
J 0
(-6925 2925);
DISPLAY 1.021277 (-6925 2925);
DISPLAY INVISIBLE (-6925 2925);
FORCEADD OFFPAGE..2
R 2
(-6675 2825);
FORCEPROP 2 LAST $XR0 99 
J 0
(-6899 2825);
DISPLAY 0.638298 (-6899 2825);
PAINT MONO (-6899 2825);
FORCEPROP 2 LAST CDS_LIB standard
J 0
(-6675 2825);
DISPLAY INVISIBLE (-6675 2825);
FORCEPROP 1 LAST OFFPAGE TRUE
J 2
(-7000 2700);
DISPLAY 0.872340 (-7000 2700);
PAINT GREEN (-7000 2700);
DISPLAY INVISIBLE (-7000 2700);
FORCEPROP 1 LAST COMMENT_BODY TRUE
J 2
(-6630 2730);
DISPLAY 0.872340 (-6630 2730);
PAINT GREEN (-6630 2730);
DISPLAY INVISIBLE (-6630 2730);
FORCEPROP 2 LAST PATH I307
J 0
(-6925 2875);
DISPLAY 1.021277 (-6925 2875);
DISPLAY INVISIBLE (-6925 2875);
FORCEADD OFFPAGE..1
(-6675 2725);
FORCEPROP 2 LAST $XR0 99 
J 0
(-6926 2725);
DISPLAY 0.638298 (-6926 2725);
PAINT MONO (-6926 2725);
FORCEPROP 2 LAST CDS_LIB standard
J 0
(-6675 2725);
DISPLAY INVISIBLE (-6675 2725);
FORCEPROP 1 LAST OFFPAGE TRUE
J 0
(-6350 2600);
DISPLAY 0.872340 (-6350 2600);
PAINT GREEN (-6350 2600);
DISPLAY INVISIBLE (-6350 2600);
FORCEPROP 1 LAST COMMENT_BODY TRUE
J 0
(-6550 2625);
DISPLAY 0.872340 (-6550 2625);
PAINT GREEN (-6550 2625);
DISPLAY INVISIBLE (-6550 2625);
FORCEPROP 2 LAST PATH I308
J 0
(-6950 2775);
DISPLAY 1.021277 (-6950 2775);
DISPLAY INVISIBLE (-6950 2775);
FORCEADD OFFPAGE..5
(-6675 2625);
FORCEPROP 2 LAST $XR0 99 
J 0
(-6899 2625);
DISPLAY 0.638298 (-6899 2625);
PAINT MONO (-6899 2625);
FORCEPROP 2 LAST CDS_LIB mstr_standard
J 0
(-6675 2625);
DISPLAY INVISIBLE (-6675 2625);
FORCEPROP 1 LAST OFFPAGE TRUE
J 0
(-6350 2500);
DISPLAY 0.872340 (-6350 2500);
PAINT GREEN (-6350 2500);
DISPLAY INVISIBLE (-6350 2500);
FORCEPROP 1 LAST COMMENT_BODY TRUE
J 0
(-6575 2550);
DISPLAY 0.872340 (-6575 2550);
PAINT GREEN (-6575 2550);
DISPLAY INVISIBLE (-6575 2550);
FORCEPROP 2 LAST PATH I309
J 0
(-6925 2675);
DISPLAY 1.021277 (-6925 2675);
DISPLAY INVISIBLE (-6925 2675);
FORCEADD OFFPAGE..2
R 2
(-6675 2475);
FORCEPROP 2 LAST $XR0 99 
J 0
(-6899 2475);
DISPLAY 0.638298 (-6899 2475);
PAINT MONO (-6899 2475);
FORCEPROP 2 LAST CDS_LIB standard
J 0
(-6675 2475);
DISPLAY INVISIBLE (-6675 2475);
FORCEPROP 1 LAST OFFPAGE TRUE
J 2
(-7000 2350);
DISPLAY 0.872340 (-7000 2350);
PAINT GREEN (-7000 2350);
DISPLAY INVISIBLE (-7000 2350);
FORCEPROP 1 LAST COMMENT_BODY TRUE
J 2
(-6630 2380);
DISPLAY 0.872340 (-6630 2380);
PAINT GREEN (-6630 2380);
DISPLAY INVISIBLE (-6630 2380);
FORCEPROP 2 LAST PATH I310
J 0
(-6925 2525);
DISPLAY 1.021277 (-6925 2525);
DISPLAY INVISIBLE (-6925 2525);
FORCEADD OFFPAGE..2
R 2
(-6675 2525);
FORCEPROP 2 LAST $XR0 99 
J 0
(-6899 2525);
DISPLAY 0.638298 (-6899 2525);
PAINT MONO (-6899 2525);
FORCEPROP 2 LAST CDS_LIB standard
J 0
(-6675 2525);
DISPLAY INVISIBLE (-6675 2525);
FORCEPROP 1 LAST OFFPAGE TRUE
J 2
(-7000 2400);
DISPLAY 0.872340 (-7000 2400);
PAINT GREEN (-7000 2400);
DISPLAY INVISIBLE (-7000 2400);
FORCEPROP 1 LAST COMMENT_BODY TRUE
J 2
(-6630 2430);
DISPLAY 0.872340 (-6630 2430);
PAINT GREEN (-6630 2430);
DISPLAY INVISIBLE (-6630 2430);
FORCEPROP 2 LAST PATH I311
J 0
(-6925 2575);
DISPLAY 1.021277 (-6925 2575);
DISPLAY INVISIBLE (-6925 2575);
FORCEADD OFFPAGE..1
(-6675 2375);
FORCEPROP 2 LAST $XR0 99 
J 0
(-6926 2375);
DISPLAY 0.638298 (-6926 2375);
PAINT MONO (-6926 2375);
FORCEPROP 2 LAST CDS_LIB standard
J 0
(-6675 2375);
DISPLAY INVISIBLE (-6675 2375);
FORCEPROP 1 LAST OFFPAGE TRUE
J 0
(-6350 2250);
DISPLAY 0.872340 (-6350 2250);
PAINT GREEN (-6350 2250);
DISPLAY INVISIBLE (-6350 2250);
FORCEPROP 1 LAST COMMENT_BODY TRUE
J 0
(-6550 2275);
DISPLAY 0.872340 (-6550 2275);
PAINT GREEN (-6550 2275);
DISPLAY INVISIBLE (-6550 2275);
FORCEPROP 2 LAST PATH I312
J 0
(-6950 2425);
DISPLAY 1.021277 (-6950 2425);
DISPLAY INVISIBLE (-6950 2425);
FORCEADD OFFPAGE..5
(-6675 2275);
FORCEPROP 2 LAST $XR0 99 
J 0
(-6899 2275);
DISPLAY 0.638298 (-6899 2275);
PAINT MONO (-6899 2275);
FORCEPROP 2 LAST CDS_LIB standard
J 0
(-6675 2275);
DISPLAY INVISIBLE (-6675 2275);
FORCEPROP 1 LAST OFFPAGE TRUE
J 0
(-6350 2150);
DISPLAY 0.872340 (-6350 2150);
PAINT GREEN (-6350 2150);
DISPLAY INVISIBLE (-6350 2150);
FORCEPROP 1 LAST COMMENT_BODY TRUE
J 0
(-6575 2200);
DISPLAY 0.872340 (-6575 2200);
PAINT GREEN (-6575 2200);
DISPLAY INVISIBLE (-6575 2200);
FORCEPROP 2 LAST PATH I313
J 0
(-6925 2325);
DISPLAY 1.021277 (-6925 2325);
DISPLAY INVISIBLE (-6925 2325);
FORCEADD Q_RES..1
(-6750 2175);
FORCEPROP 1 LAST LOCATION R501
J 0
(-7075 2175);
DISPLAY 0.489362 (-7075 2175);
PAINT SKYBLUE (-7075 2175);
FORCEPROP 0 LAST $SEC 1
J 0
(-6925 2225);
DISPLAY 0.680851 (-6925 2225);
PAINT MONO (-6925 2225);
DISPLAY INVISIBLE (-6925 2225);
FORCEPROP 0 LAST CDS_SEC 1
J 0
(-6925 2225);
DISPLAY 1.021277 (-6925 2225);
DISPLAY INVISIBLE (-6925 2225);
FORCEPROP 1 LASTPIN (-6850 2175) $PN 1
J 0
(-6838 2187);
DISPLAY 0.489362 (-6838 2187);
PAINT MONO (-6838 2187);
FORCEPROP 1 LASTPIN (-6650 2175) $PN 2
J 0
(-6688 2187);
DISPLAY 0.489362 (-6688 2187);
PAINT MONO (-6688 2187);
FORCEPROP 1 LAST PACK_TYPE 0402LF
J 0
(-7075 2150);
DISPLAY 0.489362 (-7075 2150);
PAINT SKYBLUE (-7075 2150);
FORCEPROP 1 LAST TOLERANCE 1%
J 0
(-6475 2175);
DISPLAY 0.489362 (-6475 2175);
PAINT SKYBLUE (-6475 2175);
FORCEPROP 1 LAST VALUE 15
J 2
(-6425 2175);
DISPLAY 0.489362 (-6425 2175);
PAINT SKYBLUE (-6425 2175);
FORCEPROP 1 LAST MATERIAL CHIP
J 0
(-6875 2300);
DISPLAY 0.638298 (-6875 2300);
PAINT SKYBLUE (-6875 2300);
DISPLAY INVISIBLE (-6875 2300);
FORCEPROP 1 LAST WATTAGE 1/16W
J 2
(-6525 2300);
DISPLAY 0.638298 (-6525 2300);
PAINT SKYBLUE (-6525 2300);
DISPLAY INVISIBLE (-6525 2300);
FORCEPROP 2 LAST CDS_LIB pure_quanta
J 0
(-6750 2175);
DISPLAY INVISIBLE (-6750 2175);
FORCEPROP 1 LAST PATH I314
J 0
(-6800 2325);
DISPLAY 0.978723 (-6800 2325);
PAINT WHITE (-6800 2325);
DISPLAY INVISIBLE (-6800 2325);
FORCEPROP 1 LAST PART_NUMBER CS01502FB03
J 0
(-6625 2150);
DISPLAY 0.489362 (-6625 2150);
PAINT SKYBLUE (-6625 2150);
DISPLAY INVISIBLE (-6625 2150);
FORCEADD OFFPAGE..1
(-7625 2175);
FORCEPROP 2 LAST $XR0 99 
J 0
(-7846 2175);
DISPLAY 0.638298 (-7846 2175);
PAINT MONO (-7846 2175);
FORCEPROP 2 LAST CDS_LIB mstr_standard
J 0
(-7625 2175);
DISPLAY INVISIBLE (-7625 2175);
FORCEPROP 1 LAST OFFPAGE TRUE
J 0
(-7300 2050);
DISPLAY 0.872340 (-7300 2050);
PAINT GREEN (-7300 2050);
DISPLAY INVISIBLE (-7300 2050);
FORCEPROP 1 LAST COMMENT_BODY TRUE
J 0
(-7500 2075);
DISPLAY 0.872340 (-7500 2075);
PAINT GREEN (-7500 2075);
DISPLAY INVISIBLE (-7500 2075);
FORCEPROP 2 LAST PATH I315
J 0
(-7875 2225);
DISPLAY 1.021277 (-7875 2225);
DISPLAY INVISIBLE (-7875 2225);
FORCEADD OFFPAGE..5
(-6675 2075);
FORCEPROP 2 LAST $XR0 99 
J 0
(-6899 2075);
DISPLAY 0.638298 (-6899 2075);
PAINT MONO (-6899 2075);
FORCEPROP 2 LAST CDS_LIB standard
J 0
(-6675 2075);
DISPLAY INVISIBLE (-6675 2075);
FORCEPROP 1 LAST OFFPAGE TRUE
J 0
(-6350 1950);
DISPLAY 0.872340 (-6350 1950);
PAINT GREEN (-6350 1950);
DISPLAY INVISIBLE (-6350 1950);
FORCEPROP 1 LAST COMMENT_BODY TRUE
J 0
(-6575 2000);
DISPLAY 0.872340 (-6575 2000);
PAINT GREEN (-6575 2000);
DISPLAY INVISIBLE (-6575 2000);
FORCEPROP 2 LAST PATH I316
J 0
(-6925 2125);
DISPLAY 1.021277 (-6925 2125);
DISPLAY INVISIBLE (-6925 2125);
FORCEADD CAD_NOTE..1
(-7775 2450);
FORCEPROP 0 LAST L1 R1959 PLACE CLOSE TO CPU < 25MM
J 0
(-7925 2325);
DISPLAY 0.617021 (-7925 2325);
PAINT WHITE (-7925 2325);
FORCEPROP 2 LAST CDS_LIB pure_quanta_power
J 0
(-7775 2450);
DISPLAY INVISIBLE (-7775 2450);
FORCEPROP 1 LAST COMMENT_BODY TRUE
J 0
(-7750 2550);
DISPLAY 0.574468 (-7750 2550);
PAINT WHITE (-7750 2550);
DISPLAY INVISIBLE (-7750 2550);
FORCEADD QUANTA_TITLE_BLOCK_C..1
(-100 100);
FORCEPROP 0 LAST CDS_CON_LAST_MODIFIED Thu Sep 14 16:11:55 2023
J 0
(-1985 115);
DISPLAY INVISIBLE (-1985 115);
FORCEPROP 1 LAST CUSTOM_TXT_CDS <CON_LAST_MODIFIED>
J 0
(-1985 115);
DISPLAY 0.978723 (-1985 115);
FORCEPROP 2 LAST CUSTOM_TXT_CDS <XR_PAGE_TITLE>
J 0
(-7990 5350);
DISPLAY 0.638298 (-7990 5350);
PAINT PINK (-7990 5350);
DISPLAY INVISIBLE (-7990 5350);
FORCEPROP 1 LAST CUSTOM_TXT_CDS <NAME_2>
J 0
(-3275 150);
FORCEPROP 1 LAST CUSTOM_TXT_CDS <NAME_1>
J 0
(-3275 275);
FORCEPROP 1 LAST CUSTOM_TXT_CDS <Q_NUMBER>
J 0
(-1503 203);
DISPLAY 1.212766 (-1503 203);
FORCEPROP 1 LAST CUSTOM_TXT_CDS <Q_PROJ>
J 0
(-2482 202);
DISPLAY 1.212766 (-2482 202);
FORCEPROP 1 LAST CUSTOM_TXT_CDS <Q_REV>
J 0
(-284 203);
DISPLAY 1.212766 (-284 203);
FORCEPROP 1 LAST CUSTOM_TXT_CDS <CON_PAGE_NUM> OF <CON_TOTAL_PAGES>
J 0
(-546 118);
DISPLAY 0.978723 (-546 118);
FORCEPROP 1 LAST Q_TITLE CPU1 DDR CHB
J 0
(-9400 150);
DISPLAY 2.446809 (-9400 150);
PAINT GREEN (-9400 150);
FORCEPROP 2 LAST PAGE_BORDER TRUE
J 0
(-7990 5350);
DISPLAY 0.638298 (-7990 5350);
PAINT PINK (-7990 5350);
DISPLAY INVISIBLE (-7990 5350);
FORCEPROP 2 LAST CDS_LIB pure_quanta
J 0
(-100 100);
DISPLAY INVISIBLE (-100 100);
FORCEPROP 1 LAST CDS_LMAN_SYM_OUTLINE -9475,6775,100,-125
J 0
(-100 100);
DISPLAY 0.468085 (-100 100);
PAINT GREEN (-100 100);
DISPLAY INVISIBLE (-100 100);
FORCEPROP 2 LAST CDS_XR_PAGE_TITLE CR-38 : @T6G_MB_LIB.T6G(SCH_1):PAGE38
J 0
(-7990 5350);
DISPLAY 0.638298 (-7990 5350);
PAINT PINK (-7990 5350);
DISPLAY INVISIBLE (-7990 5350);
FORCEPROP 1 LAST Q_DEPT BU9
J 1
(-3863 149);
DISPLAY 1.957447 (-3863 149);
PAINT GREEN (-3863 149);
DISPLAY INVISIBLE (-3863 149);
FORCEPROP 1 LAST COMMENT_BODY TRUE
J 0
(-88 87);
DISPLAY 0.978723 (-88 87);
PAINT GREEN (-88 87);
DISPLAY INVISIBLE (-88 87);
WIRE 17 -1 (-3400 5500)(-3400 5450);
WIRE 17 -1 (-3400 5550)(-3400 5500);
WIRE 17 -1 (-3400 5450)(-3400 5400);
WIRE 17 -1 (-3400 5400)(-3400 5350);
WIRE 17 -1 (-3400 5600)(-3400 5550);
WIRE 17 -1 (-3400 5700)(-3400 5600);
WIRE 17 -1 (-3400 5350)(-3400 5300);
WIRE 17 -1 (-3400 5300)(-3400 5250);
WIRE 17 -1 (-3400 5750)(-3400 5700);
WIRE 17 -1 (-3400 5800)(-3400 5750);
WIRE 17 -1 (-3400 5150)(-3400 5250);
WIRE 17 -1 (-3400 5100)(-3400 5150);
WIRE 17 -1 (-3400 5850)(-3400 5800);
WIRE 17 -1 (-3400 5900)(-3400 5850);
WIRE 17 -1 (-3400 5050)(-3400 5100);
WIRE 17 -1 (-3400 5000)(-3400 5050);
WIRE 17 -1 (-3400 5950)(-3400 5900);
WIRE 17 -1 (-3400 6000)(-3400 5950);
WIRE 17 -1 (-3400 5000)(-3400 4950);
WIRE 17 -1 (-3400 4950)(-3400 4900);
WIRE 17 -1 (-3400 6050)(-3400 6000);
WIRE 17 -1 (-3400 6050)(-2775 6050);
FORCEPROP 2 LAST SIG_NAME M_B_CPU1_SA_DQ<31:0>
J 2
(-2835 6060);
DISPLAY 0.489362 (-2835 6060);
WIRE 17 -1 (-3400 4900)(-3400 4850);
WIRE 17 -1 (-3400 4850)(-3400 4800);
WIRE 17 -1 (-3400 4800)(-3400 4700);
WIRE 17 -1 (-3400 4700)(-3400 4650);
WIRE 17 -1 (-3400 4650)(-3400 4600);
WIRE 17 -1 (-3400 4600)(-3400 4550);
WIRE 17 -1 (-3400 4500)(-3400 4550);
WIRE 17 -1 (-3400 4450)(-3400 4500);
WIRE 17 -1 (-3400 4400)(-3400 4450);
WIRE 17 -1 (-3400 4350)(-3400 4400);
WIRE 17 -1 (-3400 4250)(-2775 4250);
FORCEPROP 2 LAST SIG_NAME M_B_CPU1_SB_DQ<31:0>
J 2
(-2835 4260);
DISPLAY 0.489362 (-2835 4260);
WIRE 17 -1 (-3400 4250)(-3400 4200);
WIRE 17 -1 (-3400 4200)(-3400 4150);
WIRE 17 -1 (-3400 4150)(-3400 4100);
WIRE 17 -1 (-3400 4100)(-3400 4050);
WIRE 17 -1 (-3400 3150)(-3400 3100);
WIRE 17 -1 (-3400 3200)(-3400 3150);
WIRE 17 -1 (-3400 3100)(-3400 3050);
WIRE 17 -1 (-3400 3050)(-3400 3000);
WIRE 17 -1 (-3400 3200)(-3400 3250);
WIRE 17 -1 (-3400 3250)(-3400 3300);
WIRE 17 -1 (-3400 3000)(-3400 2900);
WIRE 17 -1 (-3400 2900)(-3400 2850);
WIRE 17 -1 (-3400 3300)(-3400 3350);
WIRE 17 -1 (-3400 3350)(-3400 3450);
WIRE 17 -1 (-3400 2850)(-3400 2800);
WIRE 17 -1 (-3400 2800)(-3400 2750);
WIRE 17 -1 (-3400 3500)(-3400 3450);
WIRE 17 -1 (-3400 3550)(-3400 3500);
WIRE 17 -1 (-3400 2700)(-3400 2750);
WIRE 17 -1 (-3400 2650)(-3400 2700);
WIRE 17 -1 (-3400 3600)(-3400 3550);
WIRE 17 -1 (-3400 3650)(-3400 3600);
WIRE 17 -1 (-3400 2600)(-3400 2650);
WIRE 17 -1 (-3400 2550)(-3400 2600);
WIRE 17 -1 (-3400 3700)(-3400 3650);
WIRE 17 -1 (-3400 3750)(-3400 3700);
WIRE 17 -1 (-3400 3800)(-3400 3750);
WIRE 17 -1 (-3400 3900)(-3400 3800);
WIRE 17 -1 (-3400 3950)(-3400 3900);
WIRE 17 -1 (-3400 4000)(-3400 3950);
WIRE 17 -1 (-3400 4050)(-3400 4000);
WIRE 17 -1 (-3400 2350)(-3400 2400);
WIRE 17 -1 (-3400 2350)(-3400 2300);
WIRE 17 -1 (-3400 2450)(-3400 2400);
WIRE 17 -1 (-3400 2450)(-3400 2475);
WIRE 17 -1 (-3400 2250)(-3400 2300);
WIRE 17 -1 (-3400 2200)(-3400 2250);
WIRE 17 -1 (-3400 2475)(-2900 2475);
FORCEPROP 2 LAST SIG_NAME M_B_CPU1_SA_CB<7:0>
J 2
(-2900 2485);
DISPLAY 0.489362 (-2900 2485);
WIRE 17 -1 (-3400 2150)(-3400 2200);
WIRE 17 -1 (-3400 2100)(-3400 2150);
WIRE 17 -1 (-3400 2000)(-3400 2025);
WIRE 17 -1 (-3400 2000)(-3400 1950);
WIRE 17 -1 (-3400 2025)(-2900 2025);
FORCEPROP 2 LAST SIG_NAME M_B_CPU1_SB_CB<7:0>
J 2
(-2900 2035);
DISPLAY 0.489362 (-2900 2035);
WIRE 17 -1 (-3400 1900)(-3400 1950);
WIRE 17 -1 (-3400 1900)(-3400 1850);
WIRE 17 -1 (-3400 1800)(-3400 1850);
WIRE 17 -1 (-3400 1750)(-3400 1800);
WIRE 17 -1 (-3400 1700)(-3400 1750);
WIRE 17 -1 (-3400 1650)(-3400 1700);
WIRE 17 -1 (-6125 6000)(-6125 5900);
FORCEPROP 2 LAST SIG_NAME M_B_CPU1_SA_DQS_DN<9:0>
J 2
(-6160 6010);
DISPLAY 0.489362 (-6160 6010);
WIRE 17 -1 (-6125 5900)(-6125 5800);
WIRE 17 -1 (-6125 5800)(-6125 5700);
WIRE 17 -1 (-6125 5700)(-6125 5600);
WIRE 17 -1 (-6125 5500)(-6125 5600);
WIRE 17 -1 (-6125 5400)(-6125 5500);
WIRE 17 -1 (-5925 6050)(-5925 5950);
WIRE 17 -1 (-5925 6050)(-6725 6050);
FORCEPROP 2 LAST SIG_NAME M_B_CPU1_SA_DQS_DP<9:0>
J 2
(-6160 6060);
DISPLAY 0.489362 (-6160 6060);
WIRE 17 -1 (-6125 5300)(-6125 5400);
WIRE 17 -1 (-6125 5300)(-6125 5200);
WIRE 17 -1 (-6125 5200)(-6125 5100);
WIRE 17 -1 (-5925 5950)(-5925 5850);
WIRE 17 -1 (-5925 5850)(-5925 5750);
WIRE 17 -1 (-5925 5750)(-5925 5650);
WIRE 17 -1 (-5925 5550)(-5925 5650);
WIRE 17 -1 (-5925 5450)(-5925 5550);
WIRE 17 -1 (-5925 5350)(-5925 5450);
WIRE 17 -1 (-5925 5350)(-5925 5250);
WIRE 17 -1 (-5925 5250)(-5925 5150);
WIRE 17 -1 (-5925 4500)(-5925 4600);
WIRE 17 -1 (-5925 4400)(-5925 4500);
WIRE 17 -1 (-5925 4700)(-5925 4600);
WIRE 17 -1 (-5925 4800)(-5925 4700);
WIRE 17 -1 (-5925 4300)(-5925 4400);
WIRE 17 -1 (-5925 4300)(-5925 4200);
WIRE 17 -1 (-5925 4900)(-5925 4800);
WIRE 17 -1 (-5925 5000)(-5925 4900);
WIRE 17 -1 (-5925 4200)(-5925 4100);
WIRE 17 -1 (-5925 5000)(-6725 5000);
FORCEPROP 2 LAST SIG_NAME M_B_CPU1_SB_DQS_DP<9:0>
J 2
(-6160 5010);
DISPLAY 0.489362 (-6160 5010);
WIRE 17 -1 (-6125 4950)(-6125 4850);
FORCEPROP 2 LAST SIG_NAME M_B_CPU1_SB_DQS_DN<9:0>
J 2
(-6160 4960);
DISPLAY 0.489362 (-6160 4960);
WIRE 17 -1 (-6125 4850)(-6125 4750);
WIRE 17 -1 (-6125 4750)(-6125 4650);
WIRE 17 -1 (-6125 4650)(-6125 4550);
WIRE 17 -1 (-6125 4450)(-6125 4550);
WIRE 17 -1 (-6125 4350)(-6125 4450);
WIRE 17 -1 (-6125 4250)(-6125 4350);
WIRE 17 -1 (-6125 4250)(-6125 4150);
WIRE 17 -1 (-6125 4150)(-6125 4050);
WIRE 17 -1 (-6125 3850)(-6125 3900);
WIRE 17 -1 (-6125 3800)(-6125 3850);
WIRE 17 -1 (-6125 3900)(-6625 3900);
FORCEPROP 2 LAST SIG_NAME M_B_CPU1_SA_CA<6:0>
J 0
(-6625 3910);
DISPLAY 0.489362 (-6625 3910);
WIRE 17 -1 (-6125 3450)(-6125 3500);
WIRE 17 -1 (-6125 3400)(-6125 3450);
WIRE 17 -1 (-6125 3500)(-6625 3500);
FORCEPROP 2 LAST SIG_NAME M_B_CPU1_SB_CA<6:0>
J 0
(-6625 3510);
DISPLAY 0.489362 (-6625 3510);
WIRE 17 -1 (-6125 3750)(-6125 3800);
WIRE 17 -1 (-6125 3350)(-6125 3400);
WIRE 17 -1 (-6125 3700)(-6125 3750);
WIRE 17 -1 (-6125 3650)(-6125 3700);
WIRE 17 -1 (-6125 3600)(-6125 3650);
WIRE 17 -1 (-6125 3300)(-6125 3350);
WIRE 17 -1 (-6125 3250)(-6125 3300);
WIRE 17 -1 (-6125 3200)(-6125 3250);
WIRE 17 -1 (-6125 6000)(-6725 6000);
WIRE 17 -1 (-6125 4950)(-6725 4950);
WIRE 16 -1 (-7575 2175)(-6850 2175);
FORCEPROP 2 LAST SIG_NAME M_B_CPU1_ALERT_N
J 0
(-7535 2185);
DISPLAY 0.489362 (-7535 2185);
WIRE 16 -1 (-6650 2175)(-5525 2175);
FORCEPROP 2 LAST SIG_NAME M_B_CPU1_ALERT_R_N
J 0
(-6360 2185);
DISPLAY 0.489362 (-6360 2185);
FORCEPROP 2 LASTPROP $XRERR UNIQUE?
J 0
(-6600 2185);
DISPLAY 0.638298 (-6600 2185);
PAINT MONO (-6600 2185);
DISPLAY INVISIBLE (-6600 2185);
WIRE 16 -1 (-6625 1225)(-5525 1225);
FORCEPROP 2 LAST SIG_NAME TP_M_B_CPU1_SA_TEST39B
J 0
(-6610 1235);
DISPLAY 0.489362 (-6610 1235);
FORCEPROP 2 LASTPROP $XRERR UNIQUE?
J 0
(-6865 1225);
DISPLAY 0.638298 (-6865 1225);
PAINT MONO (-6865 1225);
DISPLAY INVISIBLE (-6865 1225);
WIRE 16 -1 (-6625 3025)(-5525 3025);
FORCEPROP 2 LAST SIG_NAME M_B_CPU1_CLK_DP<0>
J 0
(-6625 3035);
DISPLAY 0.489362 (-6625 3035);
WIRE 16 -1 (-6625 2975)(-5525 2975);
FORCEPROP 2 LAST SIG_NAME M_B_CPU1_CLK_DN<0>
J 0
(-6625 2985);
DISPLAY 0.489362 (-6625 2985);
WIRE 16 -1 (-6625 2875)(-5525 2875);
FORCEPROP 2 LAST SIG_NAME M_B_CPU1_SA_CS_N<0>
J 0
(-6625 2885);
DISPLAY 0.489362 (-6625 2885);
WIRE 16 -1 (-6625 2825)(-5525 2825);
FORCEPROP 2 LAST SIG_NAME M_B_CPU1_SA_CS_N<1>
J 0
(-6625 2835);
DISPLAY 0.489362 (-6625 2835);
WIRE 16 -1 (-6625 2725)(-5525 2725);
FORCEPROP 2 LAST SIG_NAME M_B_CPU1_SA_RSP<0>
J 0
(-6625 2735);
DISPLAY 0.489362 (-6625 2735);
WIRE 16 -1 (-6625 2625)(-5525 2625);
FORCEPROP 2 LAST SIG_NAME M_B_CPU1_SA_PAR
J 0
(-6625 2635);
DISPLAY 0.489362 (-6625 2635);
WIRE 16 -1 (-6625 2475)(-5525 2475);
FORCEPROP 2 LAST SIG_NAME M_B_CPU1_SB_CS_N<1>
J 0
(-6625 2485);
DISPLAY 0.489362 (-6625 2485);
WIRE 16 -1 (-6625 2525)(-5525 2525);
FORCEPROP 2 LAST SIG_NAME M_B_CPU1_SB_CS_N<0>
J 0
(-6625 2535);
DISPLAY 0.489362 (-6625 2535);
WIRE 16 -1 (-6625 2375)(-5525 2375);
FORCEPROP 2 LAST SIG_NAME M_B_CPU1_SB_RSP<0>
J 0
(-6625 2385);
DISPLAY 0.489362 (-6625 2385);
WIRE 16 -1 (-6625 2275)(-5525 2275);
FORCEPROP 2 LAST SIG_NAME M_B_CPU1_SB_PAR
J 0
(-6625 2285);
DISPLAY 0.489362 (-6625 2285);
WIRE 16 -1 (-6625 2075)(-5525 2075);
FORCEPROP 2 LAST SIG_NAME M_B_CPU1_RESET_N
J 0
(-6625 2085);
DISPLAY 0.489362 (-6625 2085);
WIRE 16 -1 (-5825 4075)(-5525 4075);
WIRE 16 -1 (-6025 3175)(-5525 3175);
WIRE 16 -1 (-6025 3575)(-5525 3575);
WIRE 16 -1 (-6025 3225)(-5525 3225);
WIRE 16 -1 (-6025 3625)(-5525 3625);
WIRE 16 -1 (-6025 3275)(-5525 3275);
WIRE 16 -1 (-6025 3675)(-5525 3675);
WIRE 16 -1 (-6025 3325)(-5525 3325);
WIRE 16 -1 (-6025 3725)(-5525 3725);
WIRE 16 -1 (-6025 3375)(-5525 3375);
WIRE 16 -1 (-6025 3775)(-5525 3775);
WIRE 16 -1 (-6025 3425)(-5525 3425);
WIRE 16 -1 (-6025 3825)(-5525 3825);
WIRE 16 -1 (-6025 3475)(-5525 3475);
WIRE 16 -1 (-6025 3875)(-5525 3875);
WIRE 16 -1 (-6025 4025)(-5525 4025);
WIRE 16 -1 (-5825 4575)(-5525 4575);
WIRE 16 -1 (-6025 4125)(-5525 4125);
WIRE 16 -1 (-5825 4675)(-5525 4675);
WIRE 16 -1 (-6025 4225)(-5525 4225);
WIRE 16 -1 (-5825 4775)(-5525 4775);
WIRE 16 -1 (-6025 4325)(-5525 4325);
WIRE 16 -1 (-5825 4875)(-5525 4875);
WIRE 16 -1 (-6025 4425)(-5525 4425);
WIRE 16 -1 (-5825 4975)(-5525 4975);
WIRE 16 -1 (-6025 4525)(-5525 4525);
WIRE 16 -1 (-6025 5075)(-5525 5075);
WIRE 16 -1 (-6025 4625)(-5525 4625);
WIRE 16 -1 (-6025 4725)(-5525 4725);
WIRE 16 -1 (-6025 4825)(-5525 4825);
WIRE 16 -1 (-6025 4925)(-5525 4925);
WIRE 16 -1 (-5825 4175)(-5525 4175);
WIRE 16 -1 (-5825 4275)(-5525 4275);
WIRE 16 -1 (-5825 4375)(-5525 4375);
WIRE 16 -1 (-5825 4475)(-5525 4475);
WIRE 16 -1 (-5825 5125)(-5525 5125);
WIRE 16 -1 (-5825 5225)(-5525 5225);
WIRE 16 -1 (-5825 5325)(-5525 5325);
WIRE 16 -1 (-5825 5425)(-5525 5425);
WIRE 16 -1 (-5825 5525)(-5525 5525);
WIRE 16 -1 (-5825 5625)(-5525 5625);
WIRE 16 -1 (-6025 5175)(-5525 5175);
WIRE 16 -1 (-5825 5725)(-5525 5725);
WIRE 16 -1 (-6025 5275)(-5525 5275);
WIRE 16 -1 (-5825 5825)(-5525 5825);
WIRE 16 -1 (-6025 5375)(-5525 5375);
WIRE 16 -1 (-5825 5925)(-5525 5925);
WIRE 16 -1 (-6025 5475)(-5525 5475);
WIRE 16 -1 (-5825 6025)(-5525 6025);
WIRE 16 -1 (-6025 5575)(-5525 5575);
WIRE 16 -1 (-6025 5675)(-5525 5675);
WIRE 16 -1 (-6025 5775)(-5525 5775);
WIRE 16 -1 (-6025 5875)(-5525 5875);
WIRE 16 -1 (-6025 5975)(-5525 5975);
WIRE 16 -1 (-3925 1625)(-3500 1625);
WIRE 16 -1 (-3925 1675)(-3500 1675);
WIRE 16 -1 (-3925 1725)(-3500 1725);
WIRE 16 -1 (-3925 1775)(-3500 1775);
WIRE 16 -1 (-3925 1825)(-3500 1825);
WIRE 16 -1 (-3925 1875)(-3500 1875);
WIRE 16 -1 (-3925 1925)(-3500 1925);
WIRE 16 -1 (-3925 1975)(-3500 1975);
WIRE 16 -1 (-3925 2375)(-3500 2375);
WIRE 16 -1 (-3925 2425)(-3500 2425);
WIRE 16 -1 (-3925 2625)(-3500 2625);
WIRE 16 -1 (-3925 2675)(-3500 2675);
WIRE 16 -1 (-3925 2725)(-3500 2725);
WIRE 16 -1 (-3925 2775)(-3500 2775);
WIRE 16 -1 (-3925 2825)(-3500 2825);
WIRE 16 -1 (-3925 2875)(-3500 2875);
WIRE 16 -1 (-3925 2975)(-3500 2975);
WIRE 16 -1 (-3925 3025)(-3500 3025);
WIRE 16 -1 (-3925 2075)(-3500 2075);
WIRE 16 -1 (-3925 2125)(-3500 2125);
WIRE 16 -1 (-3925 2525)(-3500 2525);
WIRE 16 -1 (-3925 2175)(-3500 2175);
WIRE 16 -1 (-3925 2575)(-3500 2575);
WIRE 16 -1 (-3925 2225)(-3500 2225);
WIRE 16 -1 (-3925 2275)(-3500 2275);
WIRE 16 -1 (-3925 2325)(-3500 2325);
WIRE 16 -1 (-3925 3125)(-3500 3125);
WIRE 16 -1 (-3925 3175)(-3500 3175);
WIRE 16 -1 (-3925 3225)(-3500 3225);
WIRE 16 -1 (-3925 3725)(-3500 3725);
WIRE 16 -1 (-3925 3275)(-3500 3275);
WIRE 16 -1 (-3925 3775)(-3500 3775);
WIRE 16 -1 (-3925 3325)(-3500 3325);
WIRE 16 -1 (-3925 3875)(-3500 3875);
WIRE 16 -1 (-3925 3425)(-3500 3425);
WIRE 16 -1 (-3925 3925)(-3500 3925);
WIRE 16 -1 (-3925 3475)(-3500 3475);
WIRE 16 -1 (-3925 3975)(-3500 3975);
WIRE 16 -1 (-3925 3525)(-3500 3525);
WIRE 16 -1 (-3925 4025)(-3500 4025);
WIRE 16 -1 (-3925 3575)(-3500 3575);
WIRE 16 -1 (-3925 4075)(-3500 4075);
WIRE 16 -1 (-3925 3625)(-3500 3625);
WIRE 16 -1 (-3925 3675)(-3500 3675);
WIRE 16 -1 (-3925 3075)(-3500 3075);
WIRE 16 -1 (-3925 4675)(-3500 4675);
WIRE 16 -1 (-3925 4875)(-3500 4875);
WIRE 16 -1 (-3925 4925)(-3500 4925);
WIRE 16 -1 (-3925 4325)(-3500 4325);
WIRE 16 -1 (-3925 4375)(-3500 4375);
WIRE 16 -1 (-3925 4975)(-3500 4975);
WIRE 16 -1 (-3925 5025)(-3500 5025);
WIRE 16 -1 (-3925 4425)(-3500 4425);
WIRE 16 -1 (-3925 5075)(-3500 5075);
WIRE 16 -1 (-3925 4475)(-3500 4475);
WIRE 16 -1 (-3925 4525)(-3500 4525);
WIRE 16 -1 (-3925 4125)(-3500 4125);
WIRE 16 -1 (-3925 4575)(-3500 4575);
WIRE 16 -1 (-3925 4175)(-3500 4175);
WIRE 16 -1 (-3925 4625)(-3500 4625);
WIRE 16 -1 (-3925 4225)(-3500 4225);
WIRE 16 -1 (-3925 4775)(-3500 4775);
WIRE 16 -1 (-3925 4825)(-3500 4825);
WIRE 16 -1 (-3925 5475)(-3500 5475);
WIRE 16 -1 (-3925 5525)(-3500 5525);
WIRE 16 -1 (-3925 5575)(-3500 5575);
WIRE 16 -1 (-3925 5675)(-3500 5675);
WIRE 16 -1 (-3925 5725)(-3500 5725);
WIRE 16 -1 (-3925 5775)(-3500 5775);
WIRE 16 -1 (-3925 5825)(-3500 5825);
WIRE 16 -1 (-3925 5875)(-3500 5875);
WIRE 16 -1 (-3925 5125)(-3500 5125);
WIRE 16 -1 (-3925 5925)(-3500 5925);
WIRE 16 -1 (-3925 5225)(-3500 5225);
WIRE 16 -1 (-3925 5975)(-3500 5975);
WIRE 16 -1 (-3925 5275)(-3500 5275);
WIRE 16 -1 (-3925 6025)(-3500 6025);
WIRE 16 -1 (-3925 5325)(-3500 5325);
WIRE 16 -1 (-3925 5375)(-3500 5375);
WIRE 16 -1 (-3925 5425)(-3500 5425);
QUIT
